FILE_TYPE = MACRO_DRAWING;
SET COLOR_WIRE YELLOW;
SET COLOR_PROP ORANGE;
SET COLOR_DOT WHITE;
SET COLOR_ARC YELLOW;
SET COLOR_BODY GREEN;
SET COLOR_NOTE PURPLE;
SET PROP_DISPLAY VALUE;
SET PAGE_NUMBER P93;
FORCEADD OFFPAGE..5
(-8300 2000);
FORCEPROP 2 LAST $XR0 18 
J 0
(-8554 2000);
DISPLAY 0.638298 (-8554 2000);
PAINT MONO (-8554 2000);
FORCEPROP 2 LAST PATH I1
J 0
(-8250 2075);
DISPLAY 1.021277 (-8250 2075);
DISPLAY INVISIBLE (-8250 2075);
FORCEPROP 1 LAST COMMENT_BODY TRUE
J 0
(-8200 1925);
DISPLAY 0.872340 (-8200 1925);
PAINT GREEN (-8200 1925);
DISPLAY INVISIBLE (-8200 1925);
FORCEPROP 1 LAST OFFPAGE TRUE
J 0
(-7975 1875);
DISPLAY 0.872340 (-7975 1875);
PAINT GREEN (-7975 1875);
DISPLAY INVISIBLE (-7975 1875);
FORCEPROP 2 LAST CDS_LIB mstr_standard
J 0
(-8300 2000);
DISPLAY 0.808511 (-8300 2000);
DISPLAY INVISIBLE (-8300 2000);
FORCEADD OFFPAGE..6
(-8300 3650);
FORCEPROP 2 LAST $XR0 18 
J 0
(-8549 3650);
DISPLAY 0.638298 (-8549 3650);
PAINT MONO (-8549 3650);
FORCEPROP 2 LAST PATH I10
J 0
(-8250 3725);
DISPLAY 1.021277 (-8250 3725);
DISPLAY INVISIBLE (-8250 3725);
FORCEPROP 1 LAST COMMENT_BODY TRUE
J 0
(-8200 3575);
DISPLAY 0.872340 (-8200 3575);
PAINT GREEN (-8200 3575);
DISPLAY INVISIBLE (-8200 3575);
FORCEPROP 1 LAST OFFPAGE TRUE
J 0
(-7975 3525);
DISPLAY 0.872340 (-7975 3525);
PAINT GREEN (-7975 3525);
DISPLAY INVISIBLE (-7975 3525);
FORCEPROP 2 LAST CDS_LIB mstr_standard
J 0
(-8300 3650);
DISPLAY 0.723404 (-8300 3650);
PAINT MONO (-8300 3650);
DISPLAY INVISIBLE (-8300 3650);
FORCEADD TAP..1
(-6000 4250);
FORCEPROP 3 LASTPIN (-6050 4250) SIG_NAME M_I_CPU0_SA_DQ<7>
J 0
(-6040 4260);
DISPLAY 0.659574 (-6040 4260);
PAINT MONO (-6040 4260);
DISPLAY INVISIBLE (-6040 4260);
FORCEPROP 1 LASTPIN (-6050 4250) BN 7
J 0
(-6062 4258);
DISPLAY 0.489362 (-6062 4258);
PAINT GREEN (-6062 4258);
FORCEPROP 2 LAST CDS_LIB mstr_standard
J 0
(-6000 4250);
DISPLAY 0.723404 (-6000 4250);
PAINT MONO (-6000 4250);
DISPLAY INVISIBLE (-6000 4250);
FORCEPROP 1 LAST BODY_TYPE PLUMBING
J 0
(-6000 4300);
DISPLAY 0.872340 (-6000 4300);
PAINT GREEN (-6000 4300);
DISPLAY INVISIBLE (-6000 4300);
FORCEPROP 1 LAST HDL_TAP TRUE
J 0
(-5675 4125);
DISPLAY 0.872340 (-5675 4125);
DISPLAY INVISIBLE (-5675 4125);
FORCEPROP 1 LAST PATH I100
J 0
(-6002 4250);
DISPLAY 0.872340 (-6002 4250);
PAINT GREEN (-6002 4250);
DISPLAY INVISIBLE (-6002 4250);
FORCEADD TAP..1
(-6000 4300);
FORCEPROP 3 LASTPIN (-6050 4300) SIG_NAME M_I_CPU0_SA_DQ<8>
J 0
(-6040 4310);
DISPLAY 0.659574 (-6040 4310);
PAINT MONO (-6040 4310);
DISPLAY INVISIBLE (-6040 4310);
FORCEPROP 1 LASTPIN (-6050 4300) BN 8
J 0
(-6062 4308);
DISPLAY 0.489362 (-6062 4308);
PAINT GREEN (-6062 4308);
FORCEPROP 2 LAST CDS_LIB mstr_standard
J 0
(-6000 4300);
DISPLAY 0.723404 (-6000 4300);
PAINT MONO (-6000 4300);
DISPLAY INVISIBLE (-6000 4300);
FORCEPROP 1 LAST BODY_TYPE PLUMBING
J 0
(-6000 4350);
DISPLAY 0.872340 (-6000 4350);
PAINT GREEN (-6000 4350);
DISPLAY INVISIBLE (-6000 4350);
FORCEPROP 1 LAST HDL_TAP TRUE
J 0
(-5675 4175);
DISPLAY 0.872340 (-5675 4175);
DISPLAY INVISIBLE (-5675 4175);
FORCEPROP 1 LAST PATH I101
J 0
(-6002 4300);
DISPLAY 0.872340 (-6002 4300);
PAINT GREEN (-6002 4300);
DISPLAY INVISIBLE (-6002 4300);
FORCEADD TAP..1
(-6000 4350);
FORCEPROP 3 LASTPIN (-6050 4350) SIG_NAME M_I_CPU0_SA_DQ<9>
J 0
(-6040 4360);
DISPLAY 0.659574 (-6040 4360);
PAINT MONO (-6040 4360);
DISPLAY INVISIBLE (-6040 4360);
FORCEPROP 1 LASTPIN (-6050 4350) BN 9
J 0
(-6062 4358);
DISPLAY 0.489362 (-6062 4358);
PAINT GREEN (-6062 4358);
FORCEPROP 2 LAST CDS_LIB mstr_standard
J 0
(-6000 4350);
DISPLAY 0.723404 (-6000 4350);
PAINT MONO (-6000 4350);
DISPLAY INVISIBLE (-6000 4350);
FORCEPROP 1 LAST BODY_TYPE PLUMBING
J 0
(-6000 4400);
DISPLAY 0.872340 (-6000 4400);
PAINT GREEN (-6000 4400);
DISPLAY INVISIBLE (-6000 4400);
FORCEPROP 1 LAST HDL_TAP TRUE
J 0
(-5675 4225);
DISPLAY 0.872340 (-5675 4225);
DISPLAY INVISIBLE (-5675 4225);
FORCEPROP 1 LAST PATH I102
J 0
(-6002 4350);
DISPLAY 0.872340 (-6002 4350);
PAINT GREEN (-6002 4350);
DISPLAY INVISIBLE (-6002 4350);
FORCEADD TAP..1
(-6000 4450);
FORCEPROP 3 LASTPIN (-6050 4450) SIG_NAME M_I_CPU0_SA_DQ<11>
J 0
(-6040 4460);
DISPLAY 0.659574 (-6040 4460);
PAINT MONO (-6040 4460);
DISPLAY INVISIBLE (-6040 4460);
FORCEPROP 1 LASTPIN (-6050 4450) BN 11
J 0
(-6062 4458);
DISPLAY 0.489362 (-6062 4458);
PAINT GREEN (-6062 4458);
FORCEPROP 2 LAST CDS_LIB mstr_standard
J 0
(-6000 4450);
DISPLAY 0.723404 (-6000 4450);
PAINT MONO (-6000 4450);
DISPLAY INVISIBLE (-6000 4450);
FORCEPROP 1 LAST BODY_TYPE PLUMBING
J 0
(-6000 4500);
DISPLAY 0.872340 (-6000 4500);
PAINT GREEN (-6000 4500);
DISPLAY INVISIBLE (-6000 4500);
FORCEPROP 1 LAST HDL_TAP TRUE
J 0
(-5675 4325);
DISPLAY 0.872340 (-5675 4325);
DISPLAY INVISIBLE (-5675 4325);
FORCEPROP 1 LAST PATH I103
J 0
(-6002 4450);
DISPLAY 0.872340 (-6002 4450);
PAINT GREEN (-6002 4450);
DISPLAY INVISIBLE (-6002 4450);
FORCEADD TAP..1
(-6000 4400);
FORCEPROP 3 LASTPIN (-6050 4400) SIG_NAME M_I_CPU0_SA_DQ<10>
J 0
(-6040 4410);
DISPLAY 0.659574 (-6040 4410);
PAINT MONO (-6040 4410);
DISPLAY INVISIBLE (-6040 4410);
FORCEPROP 1 LASTPIN (-6050 4400) BN 10
J 0
(-6062 4408);
DISPLAY 0.489362 (-6062 4408);
PAINT GREEN (-6062 4408);
FORCEPROP 2 LAST CDS_LIB mstr_standard
J 0
(-6000 4400);
DISPLAY 0.723404 (-6000 4400);
PAINT MONO (-6000 4400);
DISPLAY INVISIBLE (-6000 4400);
FORCEPROP 1 LAST BODY_TYPE PLUMBING
J 0
(-6000 4450);
DISPLAY 0.872340 (-6000 4450);
PAINT GREEN (-6000 4450);
DISPLAY INVISIBLE (-6000 4450);
FORCEPROP 1 LAST HDL_TAP TRUE
J 0
(-5675 4275);
DISPLAY 0.872340 (-5675 4275);
DISPLAY INVISIBLE (-5675 4275);
FORCEPROP 1 LAST PATH I104
J 0
(-6002 4400);
DISPLAY 0.872340 (-6002 4400);
PAINT GREEN (-6002 4400);
DISPLAY INVISIBLE (-6002 4400);
FORCEADD TAP..1
(-6000 4500);
FORCEPROP 3 LASTPIN (-6050 4500) SIG_NAME M_I_CPU0_SA_DQ<12>
J 0
(-6040 4510);
DISPLAY 0.659574 (-6040 4510);
PAINT MONO (-6040 4510);
DISPLAY INVISIBLE (-6040 4510);
FORCEPROP 1 LASTPIN (-6050 4500) BN 12
J 0
(-6062 4508);
DISPLAY 0.489362 (-6062 4508);
PAINT GREEN (-6062 4508);
FORCEPROP 2 LAST CDS_LIB mstr_standard
J 0
(-6000 4500);
DISPLAY 0.723404 (-6000 4500);
PAINT MONO (-6000 4500);
DISPLAY INVISIBLE (-6000 4500);
FORCEPROP 1 LAST BODY_TYPE PLUMBING
J 0
(-6000 4550);
DISPLAY 0.872340 (-6000 4550);
PAINT GREEN (-6000 4550);
DISPLAY INVISIBLE (-6000 4550);
FORCEPROP 1 LAST HDL_TAP TRUE
J 0
(-5675 4375);
DISPLAY 0.872340 (-5675 4375);
DISPLAY INVISIBLE (-5675 4375);
FORCEPROP 1 LAST PATH I105
J 0
(-6002 4500);
DISPLAY 0.872340 (-6002 4500);
PAINT GREEN (-6002 4500);
DISPLAY INVISIBLE (-6002 4500);
FORCEADD TAP..1
(-6000 4550);
FORCEPROP 3 LASTPIN (-6050 4550) SIG_NAME M_I_CPU0_SA_DQ<13>
J 0
(-6040 4560);
DISPLAY 0.659574 (-6040 4560);
PAINT MONO (-6040 4560);
DISPLAY INVISIBLE (-6040 4560);
FORCEPROP 1 LASTPIN (-6050 4550) BN 13
J 0
(-6062 4558);
DISPLAY 0.489362 (-6062 4558);
PAINT GREEN (-6062 4558);
FORCEPROP 2 LAST CDS_LIB mstr_standard
J 0
(-6000 4550);
DISPLAY 0.723404 (-6000 4550);
PAINT MONO (-6000 4550);
DISPLAY INVISIBLE (-6000 4550);
FORCEPROP 1 LAST BODY_TYPE PLUMBING
J 0
(-6000 4600);
DISPLAY 0.872340 (-6000 4600);
PAINT GREEN (-6000 4600);
DISPLAY INVISIBLE (-6000 4600);
FORCEPROP 1 LAST HDL_TAP TRUE
J 0
(-5675 4425);
DISPLAY 0.872340 (-5675 4425);
DISPLAY INVISIBLE (-5675 4425);
FORCEPROP 1 LAST PATH I106
J 0
(-6002 4550);
DISPLAY 0.872340 (-6002 4550);
PAINT GREEN (-6002 4550);
DISPLAY INVISIBLE (-6002 4550);
FORCEADD TAP..1
(-6000 4600);
FORCEPROP 3 LASTPIN (-6050 4600) SIG_NAME M_I_CPU0_SA_DQ<14>
J 0
(-6040 4610);
DISPLAY 0.659574 (-6040 4610);
PAINT MONO (-6040 4610);
DISPLAY INVISIBLE (-6040 4610);
FORCEPROP 1 LASTPIN (-6050 4600) BN 14
J 0
(-6062 4608);
DISPLAY 0.489362 (-6062 4608);
PAINT GREEN (-6062 4608);
FORCEPROP 2 LAST CDS_LIB mstr_standard
J 0
(-6000 4600);
DISPLAY 0.723404 (-6000 4600);
PAINT MONO (-6000 4600);
DISPLAY INVISIBLE (-6000 4600);
FORCEPROP 1 LAST BODY_TYPE PLUMBING
J 0
(-6000 4650);
DISPLAY 0.872340 (-6000 4650);
PAINT GREEN (-6000 4650);
DISPLAY INVISIBLE (-6000 4650);
FORCEPROP 1 LAST HDL_TAP TRUE
J 0
(-5675 4475);
DISPLAY 0.872340 (-5675 4475);
DISPLAY INVISIBLE (-5675 4475);
FORCEPROP 1 LAST PATH I107
J 0
(-6002 4600);
DISPLAY 0.872340 (-6002 4600);
PAINT GREEN (-6002 4600);
DISPLAY INVISIBLE (-6002 4600);
FORCEADD TAP..1
(-6000 4700);
FORCEPROP 3 LASTPIN (-6050 4700) SIG_NAME M_I_CPU0_SA_DQ<16>
J 0
(-6040 4710);
DISPLAY 0.659574 (-6040 4710);
PAINT MONO (-6040 4710);
DISPLAY INVISIBLE (-6040 4710);
FORCEPROP 1 LASTPIN (-6050 4700) BN 16
J 0
(-6062 4708);
DISPLAY 0.489362 (-6062 4708);
PAINT GREEN (-6062 4708);
FORCEPROP 2 LAST CDS_LIB mstr_standard
J 0
(-6000 4700);
DISPLAY 0.723404 (-6000 4700);
PAINT MONO (-6000 4700);
DISPLAY INVISIBLE (-6000 4700);
FORCEPROP 1 LAST BODY_TYPE PLUMBING
J 0
(-6000 4750);
DISPLAY 0.872340 (-6000 4750);
PAINT GREEN (-6000 4750);
DISPLAY INVISIBLE (-6000 4750);
FORCEPROP 1 LAST HDL_TAP TRUE
J 0
(-5675 4575);
DISPLAY 0.872340 (-5675 4575);
DISPLAY INVISIBLE (-5675 4575);
FORCEPROP 1 LAST PATH I108
J 0
(-6002 4700);
DISPLAY 0.872340 (-6002 4700);
PAINT GREEN (-6002 4700);
DISPLAY INVISIBLE (-6002 4700);
FORCEADD TAP..1
(-6000 4650);
FORCEPROP 3 LASTPIN (-6050 4650) SIG_NAME M_I_CPU0_SA_DQ<15>
J 0
(-6040 4660);
DISPLAY 0.659574 (-6040 4660);
PAINT MONO (-6040 4660);
DISPLAY INVISIBLE (-6040 4660);
FORCEPROP 1 LASTPIN (-6050 4650) BN 15
J 0
(-6062 4658);
DISPLAY 0.489362 (-6062 4658);
PAINT GREEN (-6062 4658);
FORCEPROP 2 LAST CDS_LIB mstr_standard
J 0
(-6000 4650);
DISPLAY 0.723404 (-6000 4650);
PAINT MONO (-6000 4650);
DISPLAY INVISIBLE (-6000 4650);
FORCEPROP 1 LAST BODY_TYPE PLUMBING
J 0
(-6000 4700);
DISPLAY 0.872340 (-6000 4700);
PAINT GREEN (-6000 4700);
DISPLAY INVISIBLE (-6000 4700);
FORCEPROP 1 LAST HDL_TAP TRUE
J 0
(-5675 4525);
DISPLAY 0.872340 (-5675 4525);
DISPLAY INVISIBLE (-5675 4525);
FORCEPROP 1 LAST PATH I109
J 0
(-6002 4650);
DISPLAY 0.872340 (-6002 4650);
PAINT GREEN (-6002 4650);
DISPLAY INVISIBLE (-6002 4650);
FORCEADD OFFPAGE..1
(-8300 4150);
FORCEPROP 2 LAST $XR0 18 
J 0
(-8521 4150);
DISPLAY 0.638298 (-8521 4150);
PAINT MONO (-8521 4150);
FORCEPROP 2 LAST PATH I11
J 0
(-8250 4225);
DISPLAY 1.021277 (-8250 4225);
DISPLAY INVISIBLE (-8250 4225);
FORCEPROP 1 LAST COMMENT_BODY TRUE
J 0
(-8175 4050);
DISPLAY 0.872340 (-8175 4050);
PAINT GREEN (-8175 4050);
DISPLAY INVISIBLE (-8175 4050);
FORCEPROP 1 LAST OFFPAGE TRUE
J 0
(-7975 4025);
DISPLAY 0.872340 (-7975 4025);
PAINT GREEN (-7975 4025);
DISPLAY INVISIBLE (-7975 4025);
FORCEPROP 2 LAST CDS_LIB mstr_standard
J 0
(-8300 4150);
DISPLAY 0.808511 (-8300 4150);
DISPLAY INVISIBLE (-8300 4150);
FORCEADD TAP..1
(-6000 4800);
FORCEPROP 3 LASTPIN (-6050 4800) SIG_NAME M_I_CPU0_SA_DQ<18>
J 0
(-6040 4810);
DISPLAY 0.659574 (-6040 4810);
PAINT MONO (-6040 4810);
DISPLAY INVISIBLE (-6040 4810);
FORCEPROP 1 LASTPIN (-6050 4800) BN 18
J 0
(-6062 4808);
DISPLAY 0.489362 (-6062 4808);
PAINT GREEN (-6062 4808);
FORCEPROP 2 LAST CDS_LIB mstr_standard
J 0
(-6000 4800);
DISPLAY 0.723404 (-6000 4800);
PAINT MONO (-6000 4800);
DISPLAY INVISIBLE (-6000 4800);
FORCEPROP 1 LAST BODY_TYPE PLUMBING
J 0
(-6000 4850);
DISPLAY 0.872340 (-6000 4850);
PAINT GREEN (-6000 4850);
DISPLAY INVISIBLE (-6000 4850);
FORCEPROP 1 LAST HDL_TAP TRUE
J 0
(-5675 4675);
DISPLAY 0.872340 (-5675 4675);
DISPLAY INVISIBLE (-5675 4675);
FORCEPROP 1 LAST PATH I110
J 0
(-6002 4800);
DISPLAY 0.872340 (-6002 4800);
PAINT GREEN (-6002 4800);
DISPLAY INVISIBLE (-6002 4800);
FORCEADD TAP..1
(-6000 4750);
FORCEPROP 3 LASTPIN (-6050 4750) SIG_NAME M_I_CPU0_SA_DQ<17>
J 0
(-6040 4760);
DISPLAY 0.659574 (-6040 4760);
PAINT MONO (-6040 4760);
DISPLAY INVISIBLE (-6040 4760);
FORCEPROP 1 LASTPIN (-6050 4750) BN 17
J 0
(-6062 4758);
DISPLAY 0.489362 (-6062 4758);
PAINT GREEN (-6062 4758);
FORCEPROP 2 LAST CDS_LIB mstr_standard
J 0
(-6000 4750);
DISPLAY 0.723404 (-6000 4750);
PAINT MONO (-6000 4750);
DISPLAY INVISIBLE (-6000 4750);
FORCEPROP 1 LAST BODY_TYPE PLUMBING
J 0
(-6000 4800);
DISPLAY 0.872340 (-6000 4800);
PAINT GREEN (-6000 4800);
DISPLAY INVISIBLE (-6000 4800);
FORCEPROP 1 LAST HDL_TAP TRUE
J 0
(-5675 4625);
DISPLAY 0.872340 (-5675 4625);
DISPLAY INVISIBLE (-5675 4625);
FORCEPROP 1 LAST PATH I111
J 0
(-6002 4750);
DISPLAY 0.872340 (-6002 4750);
PAINT GREEN (-6002 4750);
DISPLAY INVISIBLE (-6002 4750);
FORCEADD TAP..1
(-6000 4850);
FORCEPROP 3 LASTPIN (-6050 4850) SIG_NAME M_I_CPU0_SA_DQ<19>
J 0
(-6040 4860);
DISPLAY 0.659574 (-6040 4860);
PAINT MONO (-6040 4860);
DISPLAY INVISIBLE (-6040 4860);
FORCEPROP 1 LASTPIN (-6050 4850) BN 19
J 0
(-6062 4858);
DISPLAY 0.489362 (-6062 4858);
PAINT GREEN (-6062 4858);
FORCEPROP 2 LAST CDS_LIB mstr_standard
J 0
(-6000 4850);
DISPLAY 0.723404 (-6000 4850);
PAINT MONO (-6000 4850);
DISPLAY INVISIBLE (-6000 4850);
FORCEPROP 1 LAST BODY_TYPE PLUMBING
J 0
(-6000 4900);
DISPLAY 0.872340 (-6000 4900);
PAINT GREEN (-6000 4900);
DISPLAY INVISIBLE (-6000 4900);
FORCEPROP 1 LAST HDL_TAP TRUE
J 0
(-5675 4725);
DISPLAY 0.872340 (-5675 4725);
DISPLAY INVISIBLE (-5675 4725);
FORCEPROP 1 LAST PATH I112
J 0
(-6002 4850);
DISPLAY 0.872340 (-6002 4850);
PAINT GREEN (-6002 4850);
DISPLAY INVISIBLE (-6002 4850);
FORCEADD TAP..1
(-6000 4950);
FORCEPROP 3 LASTPIN (-6050 4950) SIG_NAME M_I_CPU0_SA_DQ<21>
J 0
(-6040 4960);
DISPLAY 0.659574 (-6040 4960);
PAINT MONO (-6040 4960);
DISPLAY INVISIBLE (-6040 4960);
FORCEPROP 1 LASTPIN (-6050 4950) BN 21
J 0
(-6062 4958);
DISPLAY 0.489362 (-6062 4958);
PAINT GREEN (-6062 4958);
FORCEPROP 2 LAST CDS_LIB mstr_standard
J 0
(-6000 4950);
DISPLAY 0.723404 (-6000 4950);
PAINT MONO (-6000 4950);
DISPLAY INVISIBLE (-6000 4950);
FORCEPROP 1 LAST BODY_TYPE PLUMBING
J 0
(-6000 5000);
DISPLAY 0.872340 (-6000 5000);
PAINT GREEN (-6000 5000);
DISPLAY INVISIBLE (-6000 5000);
FORCEPROP 1 LAST HDL_TAP TRUE
J 0
(-5675 4825);
DISPLAY 0.872340 (-5675 4825);
DISPLAY INVISIBLE (-5675 4825);
FORCEPROP 1 LAST PATH I113
J 0
(-6002 4950);
DISPLAY 0.872340 (-6002 4950);
PAINT GREEN (-6002 4950);
DISPLAY INVISIBLE (-6002 4950);
FORCEADD TAP..1
(-6000 4900);
FORCEPROP 3 LASTPIN (-6050 4900) SIG_NAME M_I_CPU0_SA_DQ<20>
J 0
(-6040 4910);
DISPLAY 0.659574 (-6040 4910);
PAINT MONO (-6040 4910);
DISPLAY INVISIBLE (-6040 4910);
FORCEPROP 1 LASTPIN (-6050 4900) BN 20
J 0
(-6062 4908);
DISPLAY 0.489362 (-6062 4908);
PAINT GREEN (-6062 4908);
FORCEPROP 2 LAST CDS_LIB mstr_standard
J 0
(-6000 4900);
DISPLAY 0.723404 (-6000 4900);
PAINT MONO (-6000 4900);
DISPLAY INVISIBLE (-6000 4900);
FORCEPROP 1 LAST BODY_TYPE PLUMBING
J 0
(-6000 4950);
DISPLAY 0.872340 (-6000 4950);
PAINT GREEN (-6000 4950);
DISPLAY INVISIBLE (-6000 4950);
FORCEPROP 1 LAST HDL_TAP TRUE
J 0
(-5675 4775);
DISPLAY 0.872340 (-5675 4775);
DISPLAY INVISIBLE (-5675 4775);
FORCEPROP 1 LAST PATH I114
J 0
(-6002 4900);
DISPLAY 0.872340 (-6002 4900);
PAINT GREEN (-6002 4900);
DISPLAY INVISIBLE (-6002 4900);
FORCEADD TAP..1
(-6000 5000);
FORCEPROP 3 LASTPIN (-6050 5000) SIG_NAME M_I_CPU0_SA_DQ<22>
J 0
(-6040 5010);
DISPLAY 0.659574 (-6040 5010);
PAINT MONO (-6040 5010);
DISPLAY INVISIBLE (-6040 5010);
FORCEPROP 1 LASTPIN (-6050 5000) BN 22
J 0
(-6062 5008);
DISPLAY 0.489362 (-6062 5008);
PAINT GREEN (-6062 5008);
FORCEPROP 2 LAST CDS_LIB mstr_standard
J 0
(-6000 5000);
DISPLAY 0.723404 (-6000 5000);
PAINT MONO (-6000 5000);
DISPLAY INVISIBLE (-6000 5000);
FORCEPROP 1 LAST BODY_TYPE PLUMBING
J 0
(-6000 5050);
DISPLAY 0.872340 (-6000 5050);
PAINT GREEN (-6000 5050);
DISPLAY INVISIBLE (-6000 5050);
FORCEPROP 1 LAST HDL_TAP TRUE
J 0
(-5675 4875);
DISPLAY 0.872340 (-5675 4875);
DISPLAY INVISIBLE (-5675 4875);
FORCEPROP 1 LAST PATH I115
J 0
(-6002 5000);
DISPLAY 0.872340 (-6002 5000);
PAINT GREEN (-6002 5000);
DISPLAY INVISIBLE (-6002 5000);
FORCEADD TAP..1
(-6000 5050);
FORCEPROP 3 LASTPIN (-6050 5050) SIG_NAME M_I_CPU0_SA_DQ<23>
J 0
(-6040 5060);
DISPLAY 0.659574 (-6040 5060);
PAINT MONO (-6040 5060);
DISPLAY INVISIBLE (-6040 5060);
FORCEPROP 1 LASTPIN (-6050 5050) BN 23
J 0
(-6062 5058);
DISPLAY 0.489362 (-6062 5058);
PAINT GREEN (-6062 5058);
FORCEPROP 2 LAST CDS_LIB mstr_standard
J 0
(-6000 5050);
DISPLAY 0.723404 (-6000 5050);
PAINT MONO (-6000 5050);
DISPLAY INVISIBLE (-6000 5050);
FORCEPROP 1 LAST BODY_TYPE PLUMBING
J 0
(-6000 5100);
DISPLAY 0.872340 (-6000 5100);
PAINT GREEN (-6000 5100);
DISPLAY INVISIBLE (-6000 5100);
FORCEPROP 1 LAST HDL_TAP TRUE
J 0
(-5675 4925);
DISPLAY 0.872340 (-5675 4925);
DISPLAY INVISIBLE (-5675 4925);
FORCEPROP 1 LAST PATH I116
J 0
(-6002 5050);
DISPLAY 0.872340 (-6002 5050);
PAINT GREEN (-6002 5050);
DISPLAY INVISIBLE (-6002 5050);
FORCEADD TAP..1
(-6000 5150);
FORCEPROP 3 LASTPIN (-6050 5150) SIG_NAME M_I_CPU0_SA_DQ<25>
J 0
(-6040 5160);
DISPLAY 0.659574 (-6040 5160);
PAINT MONO (-6040 5160);
DISPLAY INVISIBLE (-6040 5160);
FORCEPROP 1 LASTPIN (-6050 5150) BN 25
J 0
(-6062 5158);
DISPLAY 0.489362 (-6062 5158);
PAINT GREEN (-6062 5158);
FORCEPROP 2 LAST CDS_LIB mstr_standard
J 0
(-6000 5150);
DISPLAY 0.723404 (-6000 5150);
PAINT MONO (-6000 5150);
DISPLAY INVISIBLE (-6000 5150);
FORCEPROP 1 LAST BODY_TYPE PLUMBING
J 0
(-6000 5200);
DISPLAY 0.872340 (-6000 5200);
PAINT GREEN (-6000 5200);
DISPLAY INVISIBLE (-6000 5200);
FORCEPROP 1 LAST HDL_TAP TRUE
J 0
(-5675 5025);
DISPLAY 0.872340 (-5675 5025);
DISPLAY INVISIBLE (-5675 5025);
FORCEPROP 1 LAST PATH I117
J 0
(-6002 5150);
DISPLAY 0.872340 (-6002 5150);
PAINT GREEN (-6002 5150);
DISPLAY INVISIBLE (-6002 5150);
FORCEADD TAP..1
(-6000 5100);
FORCEPROP 3 LASTPIN (-6050 5100) SIG_NAME M_I_CPU0_SA_DQ<24>
J 0
(-6040 5110);
DISPLAY 0.659574 (-6040 5110);
PAINT MONO (-6040 5110);
DISPLAY INVISIBLE (-6040 5110);
FORCEPROP 1 LASTPIN (-6050 5100) BN 24
J 0
(-6062 5108);
DISPLAY 0.489362 (-6062 5108);
PAINT GREEN (-6062 5108);
FORCEPROP 2 LAST CDS_LIB mstr_standard
J 0
(-6000 5100);
DISPLAY 0.723404 (-6000 5100);
PAINT MONO (-6000 5100);
DISPLAY INVISIBLE (-6000 5100);
FORCEPROP 1 LAST BODY_TYPE PLUMBING
J 0
(-6000 5150);
DISPLAY 0.872340 (-6000 5150);
PAINT GREEN (-6000 5150);
DISPLAY INVISIBLE (-6000 5150);
FORCEPROP 1 LAST HDL_TAP TRUE
J 0
(-5675 4975);
DISPLAY 0.872340 (-5675 4975);
DISPLAY INVISIBLE (-5675 4975);
FORCEPROP 1 LAST PATH I118
J 0
(-6002 5100);
DISPLAY 0.872340 (-6002 5100);
PAINT GREEN (-6002 5100);
DISPLAY INVISIBLE (-6002 5100);
FORCEADD TAP..1
(-6000 5200);
FORCEPROP 3 LASTPIN (-6050 5200) SIG_NAME M_I_CPU0_SA_DQ<26>
J 0
(-6040 5210);
DISPLAY 0.659574 (-6040 5210);
PAINT MONO (-6040 5210);
DISPLAY INVISIBLE (-6040 5210);
FORCEPROP 1 LASTPIN (-6050 5200) BN 26
J 0
(-6062 5208);
DISPLAY 0.489362 (-6062 5208);
PAINT GREEN (-6062 5208);
FORCEPROP 2 LAST CDS_LIB mstr_standard
J 0
(-6000 5200);
DISPLAY 0.723404 (-6000 5200);
PAINT MONO (-6000 5200);
DISPLAY INVISIBLE (-6000 5200);
FORCEPROP 1 LAST BODY_TYPE PLUMBING
J 0
(-6000 5250);
DISPLAY 0.872340 (-6000 5250);
PAINT GREEN (-6000 5250);
DISPLAY INVISIBLE (-6000 5250);
FORCEPROP 1 LAST HDL_TAP TRUE
J 0
(-5675 5075);
DISPLAY 0.872340 (-5675 5075);
DISPLAY INVISIBLE (-5675 5075);
FORCEPROP 1 LAST PATH I119
J 0
(-6002 5200);
DISPLAY 0.872340 (-6002 5200);
PAINT GREEN (-6002 5200);
DISPLAY INVISIBLE (-6002 5200);
FORCEADD OFFPAGE..6
(-8300 4100);
FORCEPROP 2 LAST $XR0 18 
J 0
(-8549 4100);
DISPLAY 0.638298 (-8549 4100);
PAINT MONO (-8549 4100);
FORCEPROP 2 LAST PATH I12
J 0
(-8250 4175);
DISPLAY 1.021277 (-8250 4175);
DISPLAY INVISIBLE (-8250 4175);
FORCEPROP 1 LAST COMMENT_BODY TRUE
J 0
(-8200 4025);
DISPLAY 0.872340 (-8200 4025);
PAINT GREEN (-8200 4025);
DISPLAY INVISIBLE (-8200 4025);
FORCEPROP 1 LAST OFFPAGE TRUE
J 0
(-7975 3975);
DISPLAY 0.872340 (-7975 3975);
PAINT GREEN (-7975 3975);
DISPLAY INVISIBLE (-7975 3975);
FORCEPROP 2 LAST CDS_LIB mstr_standard
J 0
(-8300 4100);
DISPLAY 0.723404 (-8300 4100);
PAINT MONO (-8300 4100);
DISPLAY INVISIBLE (-8300 4100);
FORCEADD TAP..1
(-6000 5350);
FORCEPROP 3 LASTPIN (-6050 5350) SIG_NAME M_I_CPU0_SA_DQ<29>
J 0
(-6040 5360);
DISPLAY 0.659574 (-6040 5360);
PAINT MONO (-6040 5360);
DISPLAY INVISIBLE (-6040 5360);
FORCEPROP 1 LASTPIN (-6050 5350) BN 29
J 0
(-6062 5358);
DISPLAY 0.489362 (-6062 5358);
PAINT GREEN (-6062 5358);
FORCEPROP 2 LAST CDS_LIB mstr_standard
J 0
(-6000 5350);
DISPLAY 0.723404 (-6000 5350);
PAINT MONO (-6000 5350);
DISPLAY INVISIBLE (-6000 5350);
FORCEPROP 1 LAST BODY_TYPE PLUMBING
J 0
(-6000 5400);
DISPLAY 0.872340 (-6000 5400);
PAINT GREEN (-6000 5400);
DISPLAY INVISIBLE (-6000 5400);
FORCEPROP 1 LAST HDL_TAP TRUE
J 0
(-5675 5225);
DISPLAY 0.872340 (-5675 5225);
DISPLAY INVISIBLE (-5675 5225);
FORCEPROP 1 LAST PATH I120
J 0
(-6002 5350);
DISPLAY 0.872340 (-6002 5350);
PAINT GREEN (-6002 5350);
DISPLAY INVISIBLE (-6002 5350);
FORCEADD TAP..1
(-6000 5300);
FORCEPROP 3 LASTPIN (-6050 5300) SIG_NAME M_I_CPU0_SA_DQ<28>
J 0
(-6040 5310);
DISPLAY 0.659574 (-6040 5310);
PAINT MONO (-6040 5310);
DISPLAY INVISIBLE (-6040 5310);
FORCEPROP 1 LASTPIN (-6050 5300) BN 28
J 0
(-6062 5308);
DISPLAY 0.489362 (-6062 5308);
PAINT GREEN (-6062 5308);
FORCEPROP 2 LAST CDS_LIB mstr_standard
J 0
(-6000 5300);
DISPLAY 0.723404 (-6000 5300);
PAINT MONO (-6000 5300);
DISPLAY INVISIBLE (-6000 5300);
FORCEPROP 1 LAST BODY_TYPE PLUMBING
J 0
(-6000 5350);
DISPLAY 0.872340 (-6000 5350);
PAINT GREEN (-6000 5350);
DISPLAY INVISIBLE (-6000 5350);
FORCEPROP 1 LAST HDL_TAP TRUE
J 0
(-5675 5175);
DISPLAY 0.872340 (-5675 5175);
DISPLAY INVISIBLE (-5675 5175);
FORCEPROP 1 LAST PATH I121
J 0
(-6002 5300);
DISPLAY 0.872340 (-6002 5300);
PAINT GREEN (-6002 5300);
DISPLAY INVISIBLE (-6002 5300);
FORCEADD TAP..1
(-6000 5250);
FORCEPROP 3 LASTPIN (-6050 5250) SIG_NAME M_I_CPU0_SA_DQ<27>
J 0
(-6040 5260);
DISPLAY 0.659574 (-6040 5260);
PAINT MONO (-6040 5260);
DISPLAY INVISIBLE (-6040 5260);
FORCEPROP 1 LASTPIN (-6050 5250) BN 27
J 0
(-6062 5258);
DISPLAY 0.489362 (-6062 5258);
PAINT GREEN (-6062 5258);
FORCEPROP 2 LAST CDS_LIB mstr_standard
J 0
(-6000 5250);
DISPLAY 0.723404 (-6000 5250);
PAINT MONO (-6000 5250);
DISPLAY INVISIBLE (-6000 5250);
FORCEPROP 1 LAST BODY_TYPE PLUMBING
J 0
(-6000 5300);
DISPLAY 0.872340 (-6000 5300);
PAINT GREEN (-6000 5300);
DISPLAY INVISIBLE (-6000 5300);
FORCEPROP 1 LAST HDL_TAP TRUE
J 0
(-5675 5125);
DISPLAY 0.872340 (-5675 5125);
DISPLAY INVISIBLE (-5675 5125);
FORCEPROP 1 LAST PATH I122
J 0
(-6002 5250);
DISPLAY 0.872340 (-6002 5250);
PAINT GREEN (-6002 5250);
DISPLAY INVISIBLE (-6002 5250);
FORCEADD TAP..1
(-6000 5400);
FORCEPROP 3 LASTPIN (-6050 5400) SIG_NAME M_I_CPU0_SA_DQ<30>
J 0
(-6040 5410);
DISPLAY 0.659574 (-6040 5410);
PAINT MONO (-6040 5410);
DISPLAY INVISIBLE (-6040 5410);
FORCEPROP 1 LASTPIN (-6050 5400) BN 30
J 0
(-6062 5408);
DISPLAY 0.489362 (-6062 5408);
PAINT GREEN (-6062 5408);
FORCEPROP 2 LAST CDS_LIB mstr_standard
J 0
(-6000 5400);
DISPLAY 0.723404 (-6000 5400);
PAINT MONO (-6000 5400);
DISPLAY INVISIBLE (-6000 5400);
FORCEPROP 1 LAST BODY_TYPE PLUMBING
J 0
(-6000 5450);
DISPLAY 0.872340 (-6000 5450);
PAINT GREEN (-6000 5450);
DISPLAY INVISIBLE (-6000 5450);
FORCEPROP 1 LAST HDL_TAP TRUE
J 0
(-5675 5275);
DISPLAY 0.872340 (-5675 5275);
DISPLAY INVISIBLE (-5675 5275);
FORCEPROP 1 LAST PATH I123
J 0
(-6002 5400);
DISPLAY 0.872340 (-6002 5400);
PAINT GREEN (-6002 5400);
DISPLAY INVISIBLE (-6002 5400);
FORCEADD TAP..1
(-6000 5450);
FORCEPROP 3 LASTPIN (-6050 5450) SIG_NAME M_I_CPU0_SA_DQ<31>
J 0
(-6040 5460);
DISPLAY 0.659574 (-6040 5460);
PAINT MONO (-6040 5460);
DISPLAY INVISIBLE (-6040 5460);
FORCEPROP 1 LASTPIN (-6050 5450) BN 31
J 0
(-6062 5458);
DISPLAY 0.489362 (-6062 5458);
PAINT GREEN (-6062 5458);
FORCEPROP 2 LAST CDS_LIB mstr_standard
J 0
(-6000 5450);
DISPLAY 0.723404 (-6000 5450);
PAINT MONO (-6000 5450);
DISPLAY INVISIBLE (-6000 5450);
FORCEPROP 1 LAST BODY_TYPE PLUMBING
J 0
(-6000 5500);
DISPLAY 0.872340 (-6000 5500);
PAINT GREEN (-6000 5500);
DISPLAY INVISIBLE (-6000 5500);
FORCEPROP 1 LAST HDL_TAP TRUE
J 0
(-5675 5325);
DISPLAY 0.872340 (-5675 5325);
DISPLAY INVISIBLE (-5675 5325);
FORCEPROP 1 LAST PATH I124
J 0
(-6002 5450);
DISPLAY 0.872340 (-6002 5450);
PAINT GREEN (-6002 5450);
DISPLAY INVISIBLE (-6002 5450);
FORCEADD OFFPAGE..3
(-5325 5475);
FORCEPROP 2 LAST $XR0 18 
J 0
(-5111 5475);
DISPLAY 0.638298 (-5111 5475);
PAINT MONO (-5111 5475);
FORCEPROP 2 LAST PATH I125
J 0
(-5125 5550);
DISPLAY 1.021277 (-5125 5550);
DISPLAY INVISIBLE (-5125 5550);
FORCEPROP 1 LAST COMMENT_BODY TRUE
J 0
(-5375 5375);
DISPLAY 0.872340 (-5375 5375);
PAINT GREEN (-5375 5375);
DISPLAY INVISIBLE (-5375 5375);
FORCEPROP 1 LAST OFFPAGE TRUE
J 0
(-5000 5350);
DISPLAY 0.872340 (-5000 5350);
PAINT GREEN (-5000 5350);
DISPLAY INVISIBLE (-5000 5350);
FORCEPROP 2 LAST CDS_LIB mstr_standard
J 0
(-5325 5475);
DISPLAY 0.723404 (-5325 5475);
PAINT MONO (-5325 5475);
DISPLAY INVISIBLE (-5325 5475);
FORCEADD OFFPAGE..5
(-7200 1475);
FORCEPROP 2 LAST $XR0 93 
J 0
(-7424 1475);
DISPLAY 0.638298 (-7424 1475);
PAINT MONO (-7424 1475);
FORCEPROP 2 LAST PATH I126
J 0
(-7450 1525);
DISPLAY 1.021277 (-7450 1525);
DISPLAY INVISIBLE (-7450 1525);
FORCEPROP 1 LAST COMMENT_BODY TRUE
J 0
(-7100 1400);
DISPLAY 0.872340 (-7100 1400);
PAINT GREEN (-7100 1400);
DISPLAY INVISIBLE (-7100 1400);
FORCEPROP 1 LAST OFFPAGE TRUE
J 0
(-6875 1350);
DISPLAY 0.872340 (-6875 1350);
PAINT GREEN (-6875 1350);
DISPLAY INVISIBLE (-6875 1350);
FORCEPROP 2 LAST CDS_LIB mstr_standard
J 0
(-7200 1475);
DISPLAY 0.808511 (-7200 1475);
DISPLAY INVISIBLE (-7200 1475);
FORCEPROP 2 LAST BOM_COST MEM
J 0
(-7275 1550);
DISPLAY 0.808511 (-7275 1550);
DISPLAY INVISIBLE (-7275 1550);
FORCEADD GND..1
(-6425 1150);
FORCEPROP 3 LASTPIN (-6425 1200) SIG_NAME GND\g
J 0
(-6415 1210);
DISPLAY 0.659574 (-6415 1210);
PAINT MONO (-6415 1210);
DISPLAY INVISIBLE (-6415 1210);
FORCEPROP 2 LAST BOM_COST MEM
J 0
(-6525 1225);
DISPLAY 0.808511 (-6525 1225);
DISPLAY INVISIBLE (-6525 1225);
FORCEPROP 2 LAST CDS_LIB mstr_symbols
J 0
(-6425 1150);
DISPLAY 0.808511 (-6425 1150);
DISPLAY INVISIBLE (-6425 1150);
FORCEPROP 1 LAST SIZE 1B
J 0
(-6350 1100);
DISPLAY 0.851064 (-6350 1100);
PAINT GREEN (-6350 1100);
DISPLAY INVISIBLE (-6350 1100);
FORCEPROP 1 LAST BODY_TYPE PLUMBING
J 0
(-6470 1107);
DISPLAY 0.340426 (-6470 1107);
PAINT GREEN (-6470 1107);
DISPLAY INVISIBLE (-6470 1107);
FORCEPROP 1 LAST PATH I127
J 0
(-6350 1150);
DISPLAY 0.872340 (-6350 1150);
PAINT AQUA (-6350 1150);
DISPLAY INVISIBLE (-6350 1150);
FORCEPROP 1 LAST VOLTAGE 0.0
J 0
(-6470 1107);
DISPLAY 0.723404 (-6470 1107);
PAINT SKYBLUE (-6470 1107);
DISPLAY INVISIBLE (-6470 1107);
FORCEPROP 1 LAST HDL_POWER GND
J 0
(-6425 1300);
DISPLAY 0.851064 (-6425 1300);
PAINT GREEN (-6425 1300);
DISPLAY INVISIBLE (-6425 1300);
FORCEADD Q_RES..2
(-6425 1300);
FORCEPROP 1 LAST LOCATION R766
J 0
(-6380 1425);
DISPLAY 0.489362 (-6380 1425);
PAINT SKYBLUE (-6380 1425);
FORCEPROP 0 LAST $SEC 1
J 0
(-6375 1475);
DISPLAY 0.680851 (-6375 1475);
PAINT MONO (-6375 1475);
DISPLAY INVISIBLE (-6375 1475);
FORCEPROP 0 LAST CDS_SEC 1
J 0
(-6375 1475);
DISPLAY 1.021277 (-6375 1475);
DISPLAY INVISIBLE (-6375 1475);
FORCEPROP 1 LASTPIN (-6425 1400) $PN 1
J 0
(-6420 1362);
DISPLAY 0.489362 (-6420 1362);
PAINT MONO (-6420 1362);
FORCEPROP 1 LASTPIN (-6425 1200) $PN 2
J 0
(-6420 1210);
DISPLAY 0.489362 (-6420 1210);
PAINT MONO (-6420 1210);
FORCEPROP 1 LAST WATTAGE 1/16W
J 0
(-6385 1275);
DISPLAY 0.489362 (-6385 1275);
PAINT SKYBLUE (-6385 1275);
FORCEPROP 1 LAST MATERIAL CHIP
J 0
(-6385 1225);
DISPLAY 0.489362 (-6385 1225);
PAINT SKYBLUE (-6385 1225);
FORCEPROP 1 LAST TOLERANCE 1%
J 0
(-6380 1325);
DISPLAY 0.489362 (-6380 1325);
PAINT SKYBLUE (-6380 1325);
FORCEPROP 1 LAST VALUE 23.2K
J 0
(-6380 1375);
DISPLAY 0.489362 (-6380 1375);
PAINT SKYBLUE (-6380 1375);
FORCEPROP 1 LAST PART_NUMBER TMP_QCS32322FB11
J 0
(-6385 1175);
DISPLAY 0.489362 (-6385 1175);
PAINT SKYBLUE (-6385 1175);
FORCEPROP 1 LAST PACK_TYPE 0402LF
J 0
(-6385 1125);
DISPLAY 0.489362 (-6385 1125);
PAINT SKYBLUE (-6385 1125);
FORCEPROP 2 LAST CDS_LIB pure_quanta
J 0
(-6425 1300);
DISPLAY INVISIBLE (-6425 1300);
FORCEPROP 1 LAST PATH I128
J 0
(-6375 1475);
DISPLAY 0.978723 (-6375 1475);
PAINT WHITE (-6375 1475);
DISPLAY INVISIBLE (-6375 1475);
FORCEADD OFFPAGE..1
(-8300 4200);
FORCEPROP 2 LAST $XR0 18 
J 0
(-8521 4200);
DISPLAY 0.638298 (-8521 4200);
PAINT MONO (-8521 4200);
FORCEPROP 2 LAST PATH I13
J 0
(-8250 4275);
DISPLAY 1.021277 (-8250 4275);
DISPLAY INVISIBLE (-8250 4275);
FORCEPROP 1 LAST COMMENT_BODY TRUE
J 0
(-8175 4100);
DISPLAY 0.872340 (-8175 4100);
PAINT GREEN (-8175 4100);
DISPLAY INVISIBLE (-8175 4100);
FORCEPROP 1 LAST OFFPAGE TRUE
J 0
(-7975 4075);
DISPLAY 0.872340 (-7975 4075);
PAINT GREEN (-7975 4075);
DISPLAY INVISIBLE (-7975 4075);
FORCEPROP 2 LAST CDS_LIB mstr_standard
J 0
(-8300 4200);
DISPLAY 0.723404 (-8300 4200);
PAINT MONO (-8300 4200);
DISPLAY INVISIBLE (-8300 4200);
FORCEADD OFFPAGE..1
(-8300 4300);
FORCEPROP 2 LAST $XR0 18 
J 0
(-8521 4300);
DISPLAY 0.638298 (-8521 4300);
PAINT MONO (-8521 4300);
FORCEPROP 2 LAST PATH I14
J 0
(-8250 4375);
DISPLAY 1.021277 (-8250 4375);
DISPLAY INVISIBLE (-8250 4375);
FORCEPROP 1 LAST COMMENT_BODY TRUE
J 0
(-8175 4200);
DISPLAY 0.872340 (-8175 4200);
PAINT GREEN (-8175 4200);
DISPLAY INVISIBLE (-8175 4200);
FORCEPROP 1 LAST OFFPAGE TRUE
J 0
(-7975 4175);
DISPLAY 0.872340 (-7975 4175);
PAINT GREEN (-7975 4175);
DISPLAY INVISIBLE (-7975 4175);
FORCEPROP 2 LAST CDS_LIB mstr_standard
J 0
(-8300 4300);
DISPLAY 0.808511 (-8300 4300);
DISPLAY INVISIBLE (-8300 4300);
FORCEADD GND..1
(-2125 2025);
FORCEPROP 3 LASTPIN (-2125 2075) SIG_NAME GND\g
J 0
(-2115 2085);
DISPLAY 0.659574 (-2115 2085);
PAINT MONO (-2115 2085);
DISPLAY INVISIBLE (-2115 2085);
FORCEPROP 2 LAST CDS_LIB mstr_symbols
J 0
(-2125 2025);
DISPLAY 0.723404 (-2125 2025);
DISPLAY INVISIBLE (-2125 2025);
FORCEPROP 1 LAST SIZE 1B
J 0
(-2050 1975);
DISPLAY 0.851064 (-2050 1975);
PAINT GREEN (-2050 1975);
DISPLAY INVISIBLE (-2050 1975);
FORCEPROP 1 LAST BODY_TYPE PLUMBING
J 0
(-2170 1982);
DISPLAY 0.340426 (-2170 1982);
PAINT GREEN (-2170 1982);
DISPLAY INVISIBLE (-2170 1982);
FORCEPROP 1 LAST PATH I141
J 0
(-2050 2025);
DISPLAY 0.872340 (-2050 2025);
PAINT AQUA (-2050 2025);
DISPLAY INVISIBLE (-2050 2025);
FORCEPROP 1 LAST VOLTAGE 0.0
J 0
(-2170 1982);
DISPLAY 0.723404 (-2170 1982);
PAINT SKYBLUE (-2170 1982);
DISPLAY INVISIBLE (-2170 1982);
FORCEPROP 1 LAST HDL_POWER GND
J 0
(-2125 2175);
DISPLAY 0.851064 (-2125 2175);
PAINT GREEN (-2125 2175);
DISPLAY INVISIBLE (-2125 2175);
FORCEADD GND..1
(-325 1800);
FORCEPROP 3 LASTPIN (-325 1850) SIG_NAME GND\g
J 0
(-315 1860);
DISPLAY 0.659574 (-315 1860);
PAINT MONO (-315 1860);
DISPLAY INVISIBLE (-315 1860);
FORCEPROP 2 LAST CDS_LIB mstr_symbols
J 0
(-325 1800);
DISPLAY 0.723404 (-325 1800);
DISPLAY INVISIBLE (-325 1800);
FORCEPROP 1 LAST SIZE 1B
J 0
(-250 1750);
DISPLAY 0.851064 (-250 1750);
PAINT GREEN (-250 1750);
DISPLAY INVISIBLE (-250 1750);
FORCEPROP 1 LAST BODY_TYPE PLUMBING
J 0
(-370 1757);
DISPLAY 0.340426 (-370 1757);
PAINT GREEN (-370 1757);
DISPLAY INVISIBLE (-370 1757);
FORCEPROP 1 LAST PATH I142
J 0
(-250 1800);
DISPLAY 0.872340 (-250 1800);
PAINT AQUA (-250 1800);
DISPLAY INVISIBLE (-250 1800);
FORCEPROP 1 LAST VOLTAGE 0.0
J 0
(-370 1757);
DISPLAY 0.723404 (-370 1757);
PAINT SKYBLUE (-370 1757);
DISPLAY INVISIBLE (-370 1757);
FORCEPROP 1 LAST HDL_POWER GND
J 0
(-325 1950);
DISPLAY 0.851064 (-325 1950);
PAINT GREEN (-325 1950);
DISPLAY INVISIBLE (-325 1950);
FORCEADD SCONN288_DDR506112002KQ..3
(-1225 3800);
FORCEPROP 1 LAST LOCATION J18
J 0
(-1675 5775);
DISPLAY 0.468085 (-1675 5775);
PAINT SKYBLUE (-1675 5775);
FORCEPROP 0 LAST $SEC 3
J 0
(-1675 5925);
DISPLAY 0.680851 (-1675 5925);
PAINT MONO (-1675 5925);
DISPLAY INVISIBLE (-1675 5925);
FORCEPROP 2 LAST CDS_SEC 3
J 0
(-1675 5925);
DISPLAY 1.021277 (-1675 5925);
DISPLAY INVISIBLE (-1675 5925);
FORCEPROP 0 LASTPIN (-625 2200) $PN G1
J 0
(-615 2210);
DISPLAY 0.680851 (-615 2210);
PAINT MONO (-615 2210);
FORCEPROP 0 LASTPIN (-625 2150) $PN G2
J 0
(-615 2160);
DISPLAY 0.680851 (-615 2160);
PAINT MONO (-615 2160);
FORCEPROP 0 LASTPIN (-625 2100) $PN G3
J 0
(-615 2110);
DISPLAY 0.680851 (-615 2110);
PAINT MONO (-615 2110);
FORCEPROP 0 LASTPIN (-1825 5350) $PN 1
J 2
(-1835 5360);
DISPLAY 0.680851 (-1835 5360);
PAINT MONO (-1835 5360);
FORCEPROP 0 LASTPIN (-1825 5400) $PN 145
J 2
(-1835 5410);
DISPLAY 0.680851 (-1835 5410);
PAINT MONO (-1835 5410);
FORCEPROP 0 LASTPIN (-1825 5450) $PN 146
J 2
(-1835 5460);
DISPLAY 0.680851 (-1835 5460);
PAINT MONO (-1835 5460);
FORCEPROP 0 LASTPIN (-625 2300) $PN 6
J 0
(-615 2310);
DISPLAY 0.680851 (-615 2310);
PAINT MONO (-615 2310);
FORCEPROP 0 LASTPIN (-625 2350) $PN 8
J 0
(-615 2360);
DISPLAY 0.680851 (-615 2360);
PAINT MONO (-615 2360);
FORCEPROP 0 LASTPIN (-625 2400) $PN 10
J 0
(-615 2410);
DISPLAY 0.680851 (-615 2410);
PAINT MONO (-615 2410);
FORCEPROP 0 LASTPIN (-625 2450) $PN 13
J 0
(-615 2460);
DISPLAY 0.680851 (-615 2460);
PAINT MONO (-615 2460);
FORCEPROP 0 LASTPIN (-625 2500) $PN 15
J 0
(-615 2510);
DISPLAY 0.680851 (-615 2510);
PAINT MONO (-615 2510);
FORCEPROP 0 LASTPIN (-625 2550) $PN 17
J 0
(-615 2560);
DISPLAY 0.680851 (-615 2560);
PAINT MONO (-615 2560);
FORCEPROP 0 LASTPIN (-625 2600) $PN 19
J 0
(-615 2610);
DISPLAY 0.680851 (-615 2610);
PAINT MONO (-615 2610);
FORCEPROP 0 LASTPIN (-625 2650) $PN 21
J 0
(-615 2660);
DISPLAY 0.680851 (-615 2660);
PAINT MONO (-615 2660);
FORCEPROP 0 LASTPIN (-625 2700) $PN 24
J 0
(-615 2710);
DISPLAY 0.680851 (-615 2710);
PAINT MONO (-615 2710);
FORCEPROP 0 LASTPIN (-625 2750) $PN 26
J 0
(-615 2760);
DISPLAY 0.680851 (-615 2760);
PAINT MONO (-615 2760);
FORCEPROP 0 LASTPIN (-625 2800) $PN 28
J 0
(-615 2810);
DISPLAY 0.680851 (-615 2810);
PAINT MONO (-615 2810);
FORCEPROP 0 LASTPIN (-625 2850) $PN 30
J 0
(-615 2860);
DISPLAY 0.680851 (-615 2860);
PAINT MONO (-615 2860);
FORCEPROP 0 LASTPIN (-625 2900) $PN 32
J 0
(-615 2910);
DISPLAY 0.680851 (-615 2910);
PAINT MONO (-615 2910);
FORCEPROP 0 LASTPIN (-625 2950) $PN 35
J 0
(-615 2960);
DISPLAY 0.680851 (-615 2960);
PAINT MONO (-615 2960);
FORCEPROP 0 LASTPIN (-625 3000) $PN 37
J 0
(-615 3010);
DISPLAY 0.680851 (-615 3010);
PAINT MONO (-615 3010);
FORCEPROP 0 LASTPIN (-625 3050) $PN 39
J 0
(-615 3060);
DISPLAY 0.680851 (-615 3060);
PAINT MONO (-615 3060);
FORCEPROP 0 LASTPIN (-625 3100) $PN 41
J 0
(-615 3110);
DISPLAY 0.680851 (-615 3110);
PAINT MONO (-615 3110);
FORCEPROP 0 LASTPIN (-625 3150) $PN 43
J 0
(-615 3160);
DISPLAY 0.680851 (-615 3160);
PAINT MONO (-615 3160);
FORCEPROP 0 LASTPIN (-625 3200) $PN 46
J 0
(-615 3210);
DISPLAY 0.680851 (-615 3210);
PAINT MONO (-615 3210);
FORCEPROP 0 LASTPIN (-625 3250) $PN 48
J 0
(-615 3260);
DISPLAY 0.680851 (-615 3260);
PAINT MONO (-615 3260);
FORCEPROP 0 LASTPIN (-625 3300) $PN 50
J 0
(-615 3310);
DISPLAY 0.680851 (-615 3310);
PAINT MONO (-615 3310);
FORCEPROP 0 LASTPIN (-625 3350) $PN 52
J 0
(-615 3360);
DISPLAY 0.680851 (-615 3360);
PAINT MONO (-615 3360);
FORCEPROP 0 LASTPIN (-625 3400) $PN 54
J 0
(-615 3410);
DISPLAY 0.680851 (-615 3410);
PAINT MONO (-615 3410);
FORCEPROP 0 LASTPIN (-625 3450) $PN 57
J 0
(-615 3460);
DISPLAY 0.680851 (-615 3460);
PAINT MONO (-615 3460);
FORCEPROP 0 LASTPIN (-625 3500) $PN 59
J 0
(-615 3510);
DISPLAY 0.680851 (-615 3510);
PAINT MONO (-615 3510);
FORCEPROP 0 LASTPIN (-625 3550) $PN 61
J 0
(-615 3560);
DISPLAY 0.680851 (-615 3560);
PAINT MONO (-615 3560);
FORCEPROP 0 LASTPIN (-625 3600) $PN 63
J 0
(-615 3610);
DISPLAY 0.680851 (-615 3610);
PAINT MONO (-615 3610);
FORCEPROP 0 LASTPIN (-625 3650) $PN 65
J 0
(-615 3660);
DISPLAY 0.680851 (-615 3660);
PAINT MONO (-615 3660);
FORCEPROP 0 LASTPIN (-625 3700) $PN 67
J 0
(-615 3710);
DISPLAY 0.680851 (-615 3710);
PAINT MONO (-615 3710);
FORCEPROP 0 LASTPIN (-625 3750) $PN 69
J 0
(-615 3760);
DISPLAY 0.680851 (-615 3760);
PAINT MONO (-615 3760);
FORCEPROP 0 LASTPIN (-625 3800) $PN 71
J 0
(-615 3810);
DISPLAY 0.680851 (-615 3810);
PAINT MONO (-615 3810);
FORCEPROP 0 LASTPIN (-625 3850) $PN 73
J 0
(-615 3860);
DISPLAY 0.680851 (-615 3860);
PAINT MONO (-615 3860);
FORCEPROP 0 LASTPIN (-625 3900) $PN 75
J 0
(-615 3910);
DISPLAY 0.680851 (-615 3910);
PAINT MONO (-615 3910);
FORCEPROP 0 LASTPIN (-625 3950) $PN 77
J 0
(-615 3960);
DISPLAY 0.680851 (-615 3960);
PAINT MONO (-615 3960);
FORCEPROP 0 LASTPIN (-625 4000) $PN 79
J 0
(-615 4010);
DISPLAY 0.680851 (-615 4010);
PAINT MONO (-615 4010);
FORCEPROP 0 LASTPIN (-625 4050) $PN 81
J 0
(-615 4060);
DISPLAY 0.680851 (-615 4060);
PAINT MONO (-615 4060);
FORCEPROP 0 LASTPIN (-625 4100) $PN 83
J 0
(-615 4110);
DISPLAY 0.680851 (-615 4110);
PAINT MONO (-615 4110);
FORCEPROP 0 LASTPIN (-625 4150) $PN 85
J 0
(-615 4160);
DISPLAY 0.680851 (-615 4160);
PAINT MONO (-615 4160);
FORCEPROP 0 LASTPIN (-625 4200) $PN 88
J 0
(-615 4210);
DISPLAY 0.680851 (-615 4210);
PAINT MONO (-615 4210);
FORCEPROP 0 LASTPIN (-625 4250) $PN 90
J 0
(-615 4260);
DISPLAY 0.680851 (-615 4260);
PAINT MONO (-615 4260);
FORCEPROP 0 LASTPIN (-625 4300) $PN 92
J 0
(-615 4310);
DISPLAY 0.680851 (-615 4310);
PAINT MONO (-615 4310);
FORCEPROP 0 LASTPIN (-625 4350) $PN 95
J 0
(-615 4360);
DISPLAY 0.680851 (-615 4360);
PAINT MONO (-615 4360);
FORCEPROP 0 LASTPIN (-625 4400) $PN 97
J 0
(-615 4410);
DISPLAY 0.680851 (-615 4410);
PAINT MONO (-615 4410);
FORCEPROP 0 LASTPIN (-625 4450) $PN 99
J 0
(-615 4460);
DISPLAY 0.680851 (-615 4460);
PAINT MONO (-615 4460);
FORCEPROP 0 LASTPIN (-625 4500) $PN 101
J 0
(-615 4510);
DISPLAY 0.680851 (-615 4510);
PAINT MONO (-615 4510);
FORCEPROP 0 LASTPIN (-625 4550) $PN 103
J 0
(-615 4560);
DISPLAY 0.680851 (-615 4560);
PAINT MONO (-615 4560);
FORCEPROP 0 LASTPIN (-625 4600) $PN 106
J 0
(-615 4610);
DISPLAY 0.680851 (-615 4610);
PAINT MONO (-615 4610);
FORCEPROP 0 LASTPIN (-625 4650) $PN 108
J 0
(-615 4660);
DISPLAY 0.680851 (-615 4660);
PAINT MONO (-615 4660);
FORCEPROP 0 LASTPIN (-625 4700) $PN 110
J 0
(-615 4710);
DISPLAY 0.680851 (-615 4710);
PAINT MONO (-615 4710);
FORCEPROP 0 LASTPIN (-625 4750) $PN 112
J 0
(-615 4760);
DISPLAY 0.680851 (-615 4760);
PAINT MONO (-615 4760);
FORCEPROP 0 LASTPIN (-625 4800) $PN 114
J 0
(-615 4810);
DISPLAY 0.680851 (-615 4810);
PAINT MONO (-615 4810);
FORCEPROP 0 LASTPIN (-625 4850) $PN 117
J 0
(-615 4860);
DISPLAY 0.680851 (-615 4860);
PAINT MONO (-615 4860);
FORCEPROP 0 LASTPIN (-625 4900) $PN 119
J 0
(-615 4910);
DISPLAY 0.680851 (-615 4910);
PAINT MONO (-615 4910);
FORCEPROP 0 LASTPIN (-625 4950) $PN 121
J 0
(-615 4960);
DISPLAY 0.680851 (-615 4960);
PAINT MONO (-615 4960);
FORCEPROP 0 LASTPIN (-625 5000) $PN 123
J 0
(-615 5010);
DISPLAY 0.680851 (-615 5010);
PAINT MONO (-615 5010);
FORCEPROP 0 LASTPIN (-625 5050) $PN 125
J 0
(-615 5060);
DISPLAY 0.680851 (-615 5060);
PAINT MONO (-615 5060);
FORCEPROP 0 LASTPIN (-625 5100) $PN 128
J 0
(-615 5110);
DISPLAY 0.680851 (-615 5110);
PAINT MONO (-615 5110);
FORCEPROP 0 LASTPIN (-625 5150) $PN 130
J 0
(-615 5160);
DISPLAY 0.680851 (-615 5160);
PAINT MONO (-615 5160);
FORCEPROP 0 LASTPIN (-625 5200) $PN 132
J 0
(-615 5210);
DISPLAY 0.680851 (-615 5210);
PAINT MONO (-615 5210);
FORCEPROP 0 LASTPIN (-625 5250) $PN 134
J 0
(-615 5260);
DISPLAY 0.680851 (-615 5260);
PAINT MONO (-615 5260);
FORCEPROP 0 LASTPIN (-625 5300) $PN 136
J 0
(-615 5310);
DISPLAY 0.680851 (-615 5310);
PAINT MONO (-615 5310);
FORCEPROP 0 LASTPIN (-625 5350) $PN 139
J 0
(-615 5360);
DISPLAY 0.680851 (-615 5360);
PAINT MONO (-615 5360);
FORCEPROP 0 LASTPIN (-625 5400) $PN 141
J 0
(-615 5410);
DISPLAY 0.680851 (-615 5410);
PAINT MONO (-615 5410);
FORCEPROP 0 LASTPIN (-625 5450) $PN 143
J 0
(-615 5460);
DISPLAY 0.680851 (-615 5460);
PAINT MONO (-615 5460);
FORCEPROP 0 LASTPIN (-1825 2200) $PN 151
J 2
(-1835 2210);
DISPLAY 0.680851 (-1835 2210);
PAINT MONO (-1835 2210);
FORCEPROP 0 LASTPIN (-1825 2250) $PN 153
J 2
(-1835 2260);
DISPLAY 0.680851 (-1835 2260);
PAINT MONO (-1835 2260);
FORCEPROP 0 LASTPIN (-1825 2300) $PN 155
J 2
(-1835 2310);
DISPLAY 0.680851 (-1835 2310);
PAINT MONO (-1835 2310);
FORCEPROP 0 LASTPIN (-1825 2350) $PN 158
J 2
(-1835 2360);
DISPLAY 0.680851 (-1835 2360);
PAINT MONO (-1835 2360);
FORCEPROP 0 LASTPIN (-1825 2400) $PN 160
J 2
(-1835 2410);
DISPLAY 0.680851 (-1835 2410);
PAINT MONO (-1835 2410);
FORCEPROP 0 LASTPIN (-1825 2450) $PN 162
J 2
(-1835 2460);
DISPLAY 0.680851 (-1835 2460);
PAINT MONO (-1835 2460);
FORCEPROP 0 LASTPIN (-1825 2500) $PN 164
J 2
(-1835 2510);
DISPLAY 0.680851 (-1835 2510);
PAINT MONO (-1835 2510);
FORCEPROP 0 LASTPIN (-1825 2550) $PN 166
J 2
(-1835 2560);
DISPLAY 0.680851 (-1835 2560);
PAINT MONO (-1835 2560);
FORCEPROP 0 LASTPIN (-1825 2600) $PN 169
J 2
(-1835 2610);
DISPLAY 0.680851 (-1835 2610);
PAINT MONO (-1835 2610);
FORCEPROP 0 LASTPIN (-1825 2650) $PN 171
J 2
(-1835 2660);
DISPLAY 0.680851 (-1835 2660);
PAINT MONO (-1835 2660);
FORCEPROP 0 LASTPIN (-1825 2700) $PN 173
J 2
(-1835 2710);
DISPLAY 0.680851 (-1835 2710);
PAINT MONO (-1835 2710);
FORCEPROP 0 LASTPIN (-1825 2750) $PN 175
J 2
(-1835 2760);
DISPLAY 0.680851 (-1835 2760);
PAINT MONO (-1835 2760);
FORCEPROP 0 LASTPIN (-1825 2800) $PN 177
J 2
(-1835 2810);
DISPLAY 0.680851 (-1835 2810);
PAINT MONO (-1835 2810);
FORCEPROP 0 LASTPIN (-1825 2850) $PN 180
J 2
(-1835 2860);
DISPLAY 0.680851 (-1835 2860);
PAINT MONO (-1835 2860);
FORCEPROP 0 LASTPIN (-1825 2900) $PN 182
J 2
(-1835 2910);
DISPLAY 0.680851 (-1835 2910);
PAINT MONO (-1835 2910);
FORCEPROP 0 LASTPIN (-1825 2950) $PN 184
J 2
(-1835 2960);
DISPLAY 0.680851 (-1835 2960);
PAINT MONO (-1835 2960);
FORCEPROP 0 LASTPIN (-1825 3000) $PN 186
J 2
(-1835 3010);
DISPLAY 0.680851 (-1835 3010);
PAINT MONO (-1835 3010);
FORCEPROP 0 LASTPIN (-1825 3050) $PN 188
J 2
(-1835 3060);
DISPLAY 0.680851 (-1835 3060);
PAINT MONO (-1835 3060);
FORCEPROP 0 LASTPIN (-1825 3100) $PN 191
J 2
(-1835 3110);
DISPLAY 0.680851 (-1835 3110);
PAINT MONO (-1835 3110);
FORCEPROP 0 LASTPIN (-1825 3150) $PN 193
J 2
(-1835 3160);
DISPLAY 0.680851 (-1835 3160);
PAINT MONO (-1835 3160);
FORCEPROP 0 LASTPIN (-1825 3200) $PN 195
J 2
(-1835 3210);
DISPLAY 0.680851 (-1835 3210);
PAINT MONO (-1835 3210);
FORCEPROP 0 LASTPIN (-1825 3250) $PN 197
J 2
(-1835 3260);
DISPLAY 0.680851 (-1835 3260);
PAINT MONO (-1835 3260);
FORCEPROP 0 LASTPIN (-1825 3300) $PN 199
J 2
(-1835 3310);
DISPLAY 0.680851 (-1835 3310);
PAINT MONO (-1835 3310);
FORCEPROP 0 LASTPIN (-1825 3350) $PN 202
J 2
(-1835 3360);
DISPLAY 0.680851 (-1835 3360);
PAINT MONO (-1835 3360);
FORCEPROP 0 LASTPIN (-1825 3400) $PN 204
J 2
(-1835 3410);
DISPLAY 0.680851 (-1835 3410);
PAINT MONO (-1835 3410);
FORCEPROP 0 LASTPIN (-1825 3450) $PN 206
J 2
(-1835 3460);
DISPLAY 0.680851 (-1835 3460);
PAINT MONO (-1835 3460);
FORCEPROP 0 LASTPIN (-1825 3500) $PN 208
J 2
(-1835 3510);
DISPLAY 0.680851 (-1835 3510);
PAINT MONO (-1835 3510);
FORCEPROP 0 LASTPIN (-1825 3550) $PN 210
J 2
(-1835 3560);
DISPLAY 0.680851 (-1835 3560);
PAINT MONO (-1835 3560);
FORCEPROP 0 LASTPIN (-1825 3600) $PN 212
J 2
(-1835 3610);
DISPLAY 0.680851 (-1835 3610);
PAINT MONO (-1835 3610);
FORCEPROP 0 LASTPIN (-1825 3650) $PN 214
J 2
(-1835 3660);
DISPLAY 0.680851 (-1835 3660);
PAINT MONO (-1835 3660);
FORCEPROP 0 LASTPIN (-1825 3700) $PN 216
J 2
(-1835 3710);
DISPLAY 0.680851 (-1835 3710);
PAINT MONO (-1835 3710);
FORCEPROP 0 LASTPIN (-1825 3750) $PN 219
J 2
(-1835 3760);
DISPLAY 0.680851 (-1835 3760);
PAINT MONO (-1835 3760);
FORCEPROP 0 LASTPIN (-1825 3800) $PN 222
J 2
(-1835 3810);
DISPLAY 0.680851 (-1835 3810);
PAINT MONO (-1835 3810);
FORCEPROP 0 LASTPIN (-1825 3850) $PN 224
J 2
(-1835 3860);
DISPLAY 0.680851 (-1835 3860);
PAINT MONO (-1835 3860);
FORCEPROP 0 LASTPIN (-1825 3900) $PN 226
J 2
(-1835 3910);
DISPLAY 0.680851 (-1835 3910);
PAINT MONO (-1835 3910);
FORCEPROP 0 LASTPIN (-1825 3950) $PN 228
J 2
(-1835 3960);
DISPLAY 0.680851 (-1835 3960);
PAINT MONO (-1835 3960);
FORCEPROP 0 LASTPIN (-1825 4000) $PN 230
J 2
(-1835 4010);
DISPLAY 0.680851 (-1835 4010);
PAINT MONO (-1835 4010);
FORCEPROP 0 LASTPIN (-1825 4050) $PN 233
J 2
(-1835 4060);
DISPLAY 0.680851 (-1835 4060);
PAINT MONO (-1835 4060);
FORCEPROP 0 LASTPIN (-1825 4100) $PN 235
J 2
(-1835 4110);
DISPLAY 0.680851 (-1835 4110);
PAINT MONO (-1835 4110);
FORCEPROP 0 LASTPIN (-1825 4150) $PN 237
J 2
(-1835 4160);
DISPLAY 0.680851 (-1835 4160);
PAINT MONO (-1835 4160);
FORCEPROP 0 LASTPIN (-1825 4200) $PN 240
J 2
(-1835 4210);
DISPLAY 0.680851 (-1835 4210);
PAINT MONO (-1835 4210);
FORCEPROP 0 LASTPIN (-1825 4250) $PN 242
J 2
(-1835 4260);
DISPLAY 0.680851 (-1835 4260);
PAINT MONO (-1835 4260);
FORCEPROP 0 LASTPIN (-1825 4300) $PN 244
J 2
(-1835 4310);
DISPLAY 0.680851 (-1835 4310);
PAINT MONO (-1835 4310);
FORCEPROP 0 LASTPIN (-1825 4350) $PN 246
J 2
(-1835 4360);
DISPLAY 0.680851 (-1835 4360);
PAINT MONO (-1835 4360);
FORCEPROP 0 LASTPIN (-1825 4400) $PN 248
J 2
(-1835 4410);
DISPLAY 0.680851 (-1835 4410);
PAINT MONO (-1835 4410);
FORCEPROP 0 LASTPIN (-1825 4450) $PN 251
J 2
(-1835 4460);
DISPLAY 0.680851 (-1835 4460);
PAINT MONO (-1835 4460);
FORCEPROP 0 LASTPIN (-1825 4500) $PN 253
J 2
(-1835 4510);
DISPLAY 0.680851 (-1835 4510);
PAINT MONO (-1835 4510);
FORCEPROP 0 LASTPIN (-1825 4550) $PN 255
J 2
(-1835 4560);
DISPLAY 0.680851 (-1835 4560);
PAINT MONO (-1835 4560);
FORCEPROP 0 LASTPIN (-1825 4600) $PN 257
J 2
(-1835 4610);
DISPLAY 0.680851 (-1835 4610);
PAINT MONO (-1835 4610);
FORCEPROP 0 LASTPIN (-1825 4650) $PN 259
J 2
(-1835 4660);
DISPLAY 0.680851 (-1835 4660);
PAINT MONO (-1835 4660);
FORCEPROP 0 LASTPIN (-1825 4700) $PN 262
J 2
(-1835 4710);
DISPLAY 0.680851 (-1835 4710);
PAINT MONO (-1835 4710);
FORCEPROP 0 LASTPIN (-1825 4750) $PN 264
J 2
(-1835 4760);
DISPLAY 0.680851 (-1835 4760);
PAINT MONO (-1835 4760);
FORCEPROP 0 LASTPIN (-1825 4800) $PN 266
J 2
(-1835 4810);
DISPLAY 0.680851 (-1835 4810);
PAINT MONO (-1835 4810);
FORCEPROP 0 LASTPIN (-1825 4850) $PN 268
J 2
(-1835 4860);
DISPLAY 0.680851 (-1835 4860);
PAINT MONO (-1835 4860);
FORCEPROP 0 LASTPIN (-1825 4900) $PN 270
J 2
(-1835 4910);
DISPLAY 0.680851 (-1835 4910);
PAINT MONO (-1835 4910);
FORCEPROP 0 LASTPIN (-1825 4950) $PN 273
J 2
(-1835 4960);
DISPLAY 0.680851 (-1835 4960);
PAINT MONO (-1835 4960);
FORCEPROP 0 LASTPIN (-1825 5000) $PN 275
J 2
(-1835 5010);
DISPLAY 0.680851 (-1835 5010);
PAINT MONO (-1835 5010);
FORCEPROP 0 LASTPIN (-1825 5050) $PN 277
J 2
(-1835 5060);
DISPLAY 0.680851 (-1835 5060);
PAINT MONO (-1835 5060);
FORCEPROP 0 LASTPIN (-1825 5100) $PN 279
J 2
(-1835 5110);
DISPLAY 0.680851 (-1835 5110);
PAINT MONO (-1835 5110);
FORCEPROP 0 LASTPIN (-1825 5150) $PN 281
J 2
(-1835 5160);
DISPLAY 0.680851 (-1835 5160);
PAINT MONO (-1835 5160);
FORCEPROP 0 LASTPIN (-1825 5200) $PN 284
J 2
(-1835 5210);
DISPLAY 0.680851 (-1835 5210);
PAINT MONO (-1835 5210);
FORCEPROP 0 LASTPIN (-1825 5250) $PN 286
J 2
(-1835 5260);
DISPLAY 0.680851 (-1835 5260);
PAINT MONO (-1835 5260);
FORCEPROP 0 LASTPIN (-1825 5300) $PN 288
J 2
(-1835 5310);
DISPLAY 0.680851 (-1835 5310);
PAINT MONO (-1835 5310);
FORCEPROP 2 LAST VALUE SCONN288_DDR506112002KQ
J 0
(-1675 5825);
DISPLAY 0.489362 (-1675 5825);
PAINT SKYBLUE (-1675 5825);
FORCEPROP 2 LAST PART_TYPE SMLF
J 0
(-1675 5875);
DISPLAY 1.021277 (-1675 5875);
FORCEPROP 1 LAST MATERIAL IO
J 0
(-1675 5625);
DISPLAY 0.468085 (-1675 5625);
PAINT SKYBLUE (-1675 5625);
FORCEPROP 1 LAST PART_NUMBER DFHST8FS479
J 0
(-1675 5700);
DISPLAY 0.468085 (-1675 5700);
PAINT SKYBLUE (-1675 5700);
FORCEPROP 1 LAST CDS_LMAN_SYM_OUTLINE -450,1800,450,-1750
J 0
(-1225 3800);
DISPLAY 0.468085 (-1225 3800);
PAINT GREEN (-1225 3800);
DISPLAY INVISIBLE (-1225 3800);
FORCEPROP 1 LAST PATH I143
J 0
(-1225 3800);
DISPLAY 0.723404 (-1225 3800);
PAINT GREEN (-1225 3800);
DISPLAY INVISIBLE (-1225 3800);
FORCEPROP 1 LAST NEEDS_NO_SIZE TRUE
J 0
(-1225 3800);
DISPLAY 0.723404 (-1225 3800);
PAINT GREEN (-1225 3800);
DISPLAY INVISIBLE (-1225 3800);
FORCEPROP 2 LAST CDS_LIB pure_quanta
J 0
(-1225 3800);
DISPLAY INVISIBLE (-1225 3800);
FORCEADD OFFPAGE..1
(-8300 4350);
FORCEPROP 2 LAST $XR0 18 
J 0
(-8521 4350);
DISPLAY 0.638298 (-8521 4350);
PAINT MONO (-8521 4350);
FORCEPROP 2 LAST PATH I15
J 0
(-8250 4425);
DISPLAY 1.021277 (-8250 4425);
DISPLAY INVISIBLE (-8250 4425);
FORCEPROP 1 LAST COMMENT_BODY TRUE
J 0
(-8175 4250);
DISPLAY 0.872340 (-8175 4250);
PAINT GREEN (-8175 4250);
DISPLAY INVISIBLE (-8175 4250);
FORCEPROP 1 LAST OFFPAGE TRUE
J 0
(-7975 4225);
DISPLAY 0.872340 (-7975 4225);
PAINT GREEN (-7975 4225);
DISPLAY INVISIBLE (-7975 4225);
FORCEPROP 2 LAST CDS_LIB mstr_standard
J 0
(-8300 4350);
DISPLAY 0.723404 (-8300 4350);
PAINT MONO (-8300 4350);
DISPLAY INVISIBLE (-8300 4350);
FORCEADD OFFPAGE..1
(-8300 4450);
FORCEPROP 2 LAST $XR0 18 
J 0
(-8521 4450);
DISPLAY 0.638298 (-8521 4450);
PAINT MONO (-8521 4450);
FORCEPROP 2 LAST PATH I16
J 0
(-8250 4525);
DISPLAY 1.021277 (-8250 4525);
DISPLAY INVISIBLE (-8250 4525);
FORCEPROP 1 LAST COMMENT_BODY TRUE
J 0
(-8175 4350);
DISPLAY 0.872340 (-8175 4350);
PAINT GREEN (-8175 4350);
DISPLAY INVISIBLE (-8175 4350);
FORCEPROP 1 LAST OFFPAGE TRUE
J 0
(-7975 4325);
DISPLAY 0.872340 (-7975 4325);
PAINT GREEN (-7975 4325);
DISPLAY INVISIBLE (-7975 4325);
FORCEPROP 2 LAST CDS_LIB mstr_standard
J 0
(-8300 4450);
DISPLAY 0.808511 (-8300 4450);
DISPLAY INVISIBLE (-8300 4450);
FORCEADD OFFPAGE..1
(-8300 4600);
FORCEPROP 2 LAST $XR0 18 
J 0
(-8521 4600);
DISPLAY 0.638298 (-8521 4600);
PAINT MONO (-8521 4600);
FORCEPROP 2 LAST PATH I17
J 0
(-8250 4675);
DISPLAY 1.021277 (-8250 4675);
DISPLAY INVISIBLE (-8250 4675);
FORCEPROP 1 LAST COMMENT_BODY TRUE
J 0
(-8175 4500);
DISPLAY 0.872340 (-8175 4500);
PAINT GREEN (-8175 4500);
DISPLAY INVISIBLE (-8175 4500);
FORCEPROP 1 LAST OFFPAGE TRUE
J 0
(-7975 4475);
DISPLAY 0.872340 (-7975 4475);
PAINT GREEN (-7975 4475);
DISPLAY INVISIBLE (-7975 4475);
FORCEPROP 2 LAST CDS_LIB mstr_standard
J 0
(-8300 4600);
DISPLAY 0.808511 (-8300 4600);
DISPLAY INVISIBLE (-8300 4600);
FORCEADD OFFPAGE..6
(-8300 2900);
FORCEPROP 2 LAST $XR5 136 
J 0
(-9029 2900);
DISPLAY 0.638298 (-9029 2900);
PAINT MONO (-9029 2900);
FORCEPROP 2 LAST $XR4 96 
J 0
(-8909 2900);
DISPLAY 0.638298 (-8909 2900);
PAINT MONO (-8909 2900);
FORCEPROP 2 LAST $XR3 95 
J 0
(-8819 2900);
DISPLAY 0.638298 (-8819 2900);
PAINT MONO (-8819 2900);
FORCEPROP 2 LAST $XR2 94 
J 0
(-8729 2900);
DISPLAY 0.638298 (-8729 2900);
PAINT MONO (-8729 2900);
FORCEPROP 2 LAST $XR1 92 
J 0
(-8639 2900);
DISPLAY 0.638298 (-8639 2900);
PAINT MONO (-8639 2900);
FORCEPROP 2 LAST $XR0 91 
J 0
(-8549 2900);
DISPLAY 0.638298 (-8549 2900);
PAINT MONO (-8549 2900);
FORCEPROP 2 LAST PATH I179
J 0
(-8600 2950);
DISPLAY 1.021277 (-8600 2950);
DISPLAY INVISIBLE (-8600 2950);
FORCEPROP 1 LAST COMMENT_BODY TRUE
J 0
(-8200 2825);
DISPLAY 0.872340 (-8200 2825);
PAINT GREEN (-8200 2825);
DISPLAY INVISIBLE (-8200 2825);
FORCEPROP 1 LAST OFFPAGE TRUE
J 0
(-7975 2775);
DISPLAY 0.872340 (-7975 2775);
PAINT GREEN (-7975 2775);
DISPLAY INVISIBLE (-7975 2775);
FORCEPROP 2 LAST CDS_LIB mstr_standard
J 0
(-8300 2900);
DISPLAY 0.808511 (-8300 2900);
DISPLAY INVISIBLE (-8300 2900);
FORCEADD OFFPAGE..1
(-8300 4500);
FORCEPROP 2 LAST $XR0 18 
J 0
(-8521 4500);
DISPLAY 0.638298 (-8521 4500);
PAINT MONO (-8521 4500);
FORCEPROP 2 LAST PATH I18
J 0
(-8250 4575);
DISPLAY 1.021277 (-8250 4575);
DISPLAY INVISIBLE (-8250 4575);
FORCEPROP 1 LAST COMMENT_BODY TRUE
J 0
(-8175 4400);
DISPLAY 0.872340 (-8175 4400);
PAINT GREEN (-8175 4400);
DISPLAY INVISIBLE (-8175 4400);
FORCEPROP 1 LAST OFFPAGE TRUE
J 0
(-7975 4375);
DISPLAY 0.872340 (-7975 4375);
PAINT GREEN (-7975 4375);
DISPLAY INVISIBLE (-7975 4375);
FORCEPROP 2 LAST CDS_LIB mstr_standard
J 0
(-8300 4500);
DISPLAY 0.723404 (-8300 4500);
PAINT MONO (-8300 4500);
DISPLAY INVISIBLE (-8300 4500);
FORCEADD Q_CAP..1
R 2
(-8650 3275);
FORCEPROP 1 LAST LOCATION C120
J 2
(-8700 3375);
DISPLAY 0.489362 (-8700 3375);
PAINT SKYBLUE (-8700 3375);
FORCEPROP 0 LAST $SEC 1
J 0
(-8700 3425);
DISPLAY 0.680851 (-8700 3425);
PAINT MONO (-8700 3425);
DISPLAY INVISIBLE (-8700 3425);
FORCEPROP 0 LAST CDS_SEC 1
J 0
(-8700 3425);
DISPLAY 1.021277 (-8700 3425);
DISPLAY INVISIBLE (-8700 3425);
FORCEPROP 1 LASTPIN (-8650 3375) $PN 1
J 2
(-8660 3355);
DISPLAY 0.489362 (-8660 3355);
PAINT MONO (-8660 3355);
FORCEPROP 1 LASTPIN (-8650 3175) $PN 2
J 2
(-8660 3155);
DISPLAY 0.489362 (-8660 3155);
PAINT MONO (-8660 3155);
FORCEPROP 1 LAST MATERIAL X7R
J 2
(-8700 3175);
DISPLAY 0.489362 (-8700 3175);
PAINT SKYBLUE (-8700 3175);
FORCEPROP 1 LAST TOLERANCE 10%
J 2
(-8700 3225);
DISPLAY 0.489362 (-8700 3225);
PAINT SKYBLUE (-8700 3225);
FORCEPROP 1 LAST VALUE 0.1UF
J 2
(-8700 3325);
DISPLAY 0.489362 (-8700 3325);
PAINT SKYBLUE (-8700 3325);
FORCEPROP 1 LAST PART_NUMBER CH4104K1B00
J 2
(-8700 3125);
DISPLAY 0.489362 (-8700 3125);
PAINT SKYBLUE (-8700 3125);
FORCEPROP 1 LAST VOLTAGE 25V
J 2
(-8700 3275);
DISPLAY 0.489362 (-8700 3275);
PAINT SKYBLUE (-8700 3275);
FORCEPROP 1 LAST PACK_TYPE 0402
J 2
(-8700 3075);
DISPLAY 0.489362 (-8700 3075);
PAINT SKYBLUE (-8700 3075);
FORCEPROP 0 LAST BOM_COST MEM
J 2
(-8705 3420);
DISPLAY 0.595745 (-8705 3420);
PAINT MONO (-8705 3420);
DISPLAY INVISIBLE (-8705 3420);
FORCEPROP 2 LAST CDS_LIB pure_quanta
J 0
(-8650 3275);
DISPLAY INVISIBLE (-8650 3275);
FORCEPROP 1 LAST PATH I185
J 2
(-8700 3425);
DISPLAY 0.978723 (-8700 3425);
PAINT WHITE (-8700 3425);
DISPLAY INVISIBLE (-8700 3425);
FORCEPROP 0 LAST ROOM MEM_CH_A_CPU0_DIMM1
J 2
(-8705 3420);
DISPLAY 0.595745 (-8705 3420);
PAINT RED (-8705 3420);
DISPLAY INVISIBLE (-8705 3420);
FORCEADD GND..1
(-8650 3050);
FORCEPROP 3 LASTPIN (-8650 3100) SIG_NAME GND\g
J 0
(-8640 3110);
DISPLAY 0.659574 (-8640 3110);
PAINT MONO (-8640 3110);
DISPLAY INVISIBLE (-8640 3110);
FORCEPROP 2 LAST BOM_COST MEM
J 0
(-8625 3175);
DISPLAY 0.659574 (-8625 3175);
DISPLAY INVISIBLE (-8625 3175);
FORCEPROP 1 LAST SIZE 1B
J 0
(-8575 3000);
DISPLAY 0.723404 (-8575 3000);
PAINT GREEN (-8575 3000);
DISPLAY INVISIBLE (-8575 3000);
FORCEPROP 2 LAST CDS_LIB mstr_symbols
J 0
(-8650 3050);
DISPLAY 0.808511 (-8650 3050);
DISPLAY INVISIBLE (-8650 3050);
FORCEPROP 1 LAST BODY_TYPE PLUMBING
J 0
(-8695 3007);
DISPLAY 0.276596 (-8695 3007);
PAINT GREEN (-8695 3007);
DISPLAY INVISIBLE (-8695 3007);
FORCEPROP 1 LAST PATH I186
J 0
(-8575 3050);
DISPLAY 0.872340 (-8575 3050);
PAINT AQUA (-8575 3050);
DISPLAY INVISIBLE (-8575 3050);
FORCEPROP 1 LAST VOLTAGE 0
J 0
(-8670 3145);
DISPLAY 0.829787 (-8670 3145);
PAINT SKYBLUE (-8670 3145);
DISPLAY INVISIBLE (-8670 3145);
FORCEPROP 2 LAST ROOM MEM_EFGH_DECOUPLING_CAPS
J 0
(-8625 3125);
DISPLAY 0.659574 (-8625 3125);
PAINT RED (-8625 3125);
DISPLAY INVISIBLE (-8625 3125);
FORCEPROP 1 LAST HDL_POWER GND
J 0
(-8650 3200);
DISPLAY 0.723404 (-8650 3200);
PAINT GREEN (-8650 3200);
DISPLAY INVISIBLE (-8650 3200);
FORCEADD OFFPAGE..6
(-9025 2200);
FORCEPROP 2 LAST $XR5 81 
J 0
(-9274 2092);
DISPLAY 0.638298 (-9274 2092);
PAINT MONO (-9274 2092);
FORCEPROP 2 LAST $XR4 96 
J 0
(-9274 2272);
DISPLAY 0.638298 (-9274 2272);
PAINT MONO (-9274 2272);
FORCEPROP 2 LAST $XR3 95 
J 0
(-9274 2128);
DISPLAY 0.638298 (-9274 2128);
PAINT MONO (-9274 2128);
FORCEPROP 2 LAST $XR2 94 
J 0
(-9274 2236);
DISPLAY 0.638298 (-9274 2236);
PAINT MONO (-9274 2236);
FORCEPROP 2 LAST $XR1 92 
J 0
(-9274 2164);
DISPLAY 0.638298 (-9274 2164);
PAINT MONO (-9274 2164);
FORCEPROP 2 LAST $XR0 91 
J 0
(-9274 2200);
DISPLAY 0.638298 (-9274 2200);
PAINT MONO (-9274 2200);
FORCEPROP 2 LAST PATH I187
J 0
(-8975 2275);
DISPLAY 1.021277 (-8975 2275);
DISPLAY INVISIBLE (-8975 2275);
FORCEPROP 1 LAST COMMENT_BODY TRUE
J 0
(-8925 2125);
DISPLAY 0.872340 (-8925 2125);
PAINT GREEN (-8925 2125);
DISPLAY INVISIBLE (-8925 2125);
FORCEPROP 1 LAST OFFPAGE TRUE
J 0
(-8700 2075);
DISPLAY 0.872340 (-8700 2075);
PAINT GREEN (-8700 2075);
DISPLAY INVISIBLE (-8700 2075);
FORCEPROP 2 LAST CDS_LIB mstr_standard
J 0
(-9025 2200);
DISPLAY INVISIBLE (-9025 2200);
FORCEADD Q_RES..1
R 2
(-8475 2200);
FORCEPROP 1 LAST LOCATION R299
J 2
(-8425 2250);
DISPLAY 0.489362 (-8425 2250);
PAINT SKYBLUE (-8425 2250);
FORCEPROP 0 LAST $SEC 1
J 0
(-8425 2300);
DISPLAY 0.680851 (-8425 2300);
PAINT MONO (-8425 2300);
DISPLAY INVISIBLE (-8425 2300);
FORCEPROP 0 LAST CDS_SEC 1
J 0
(-8425 2300);
DISPLAY 1.021277 (-8425 2300);
DISPLAY INVISIBLE (-8425 2300);
FORCEPROP 1 LASTPIN (-8375 2200) $PN 1
J 2
(-8387 2212);
DISPLAY 0.489362 (-8387 2212);
PAINT MONO (-8387 2212);
FORCEPROP 1 LASTPIN (-8575 2200) $PN 2
J 2
(-8537 2212);
DISPLAY 0.489362 (-8537 2212);
PAINT MONO (-8537 2212);
FORCEPROP 1 LAST VALUE 0
J 0
(-8475 2150);
DISPLAY 0.489362 (-8475 2150);
PAINT SKYBLUE (-8475 2150);
FORCEPROP 2 LAST BOM_COST MEM
J 0
(-8500 2350);
DISPLAY 0.744681 (-8500 2350);
PAINT WHITE (-8500 2350);
DISPLAY INVISIBLE (-8500 2350);
FORCEPROP 2 LAST CDS_LIB pure_quanta
J 0
(-8475 2200);
DISPLAY INVISIBLE (-8475 2200);
FORCEPROP 1 LAST PATH I188
J 2
(-8425 2350);
DISPLAY 0.978723 (-8425 2350);
PAINT WHITE (-8425 2350);
DISPLAY INVISIBLE (-8425 2350);
FORCEPROP 1 LAST WATTAGE 1/16W
J 0
(-8400 2125);
DISPLAY 0.489362 (-8400 2125);
PAINT SKYBLUE (-8400 2125);
DISPLAY INVISIBLE (-8400 2125);
FORCEPROP 1 LAST MATERIAL CHIP
J 0
(-8650 2175);
DISPLAY 0.489362 (-8650 2175);
PAINT SKYBLUE (-8650 2175);
DISPLAY INVISIBLE (-8650 2175);
FORCEPROP 1 LAST TOLERANCE 5%
J 2
(-8350 2175);
DISPLAY 0.489362 (-8350 2175);
PAINT SKYBLUE (-8350 2175);
DISPLAY INVISIBLE (-8350 2175);
FORCEPROP 1 LAST PART_NUMBER CS00002JB38
J 0
(-8575 2250);
DISPLAY 0.489362 (-8575 2250);
PAINT SKYBLUE (-8575 2250);
DISPLAY INVISIBLE (-8575 2250);
FORCEPROP 1 LAST PACK_TYPE 0402LF
J 0
(-8650 2125);
DISPLAY 0.489362 (-8650 2125);
PAINT SKYBLUE (-8650 2125);
DISPLAY INVISIBLE (-8650 2125);
FORCEPROP 2 LAST ROOM RST_CPU0_PLD_TO_DIMM
J 0
(-8500 2300);
DISPLAY 0.744681 (-8500 2300);
PAINT RED (-8500 2300);
DISPLAY INVISIBLE (-8500 2300);
FORCEADD Q_RES..2
(-8350 2350);
FORCEPROP 1 LAST LOCATION R98
J 0
(-8305 2475);
DISPLAY 0.489362 (-8305 2475);
PAINT SKYBLUE (-8305 2475);
FORCEPROP 0 LAST $SEC 1
J 0
(-8300 2525);
DISPLAY 0.680851 (-8300 2525);
PAINT MONO (-8300 2525);
DISPLAY INVISIBLE (-8300 2525);
FORCEPROP 0 LAST CDS_SEC 1
J 0
(-8300 2525);
DISPLAY 1.021277 (-8300 2525);
DISPLAY INVISIBLE (-8300 2525);
FORCEPROP 1 LASTPIN (-8350 2450) $PN 1
J 0
(-8345 2412);
DISPLAY 0.489362 (-8345 2412);
PAINT MONO (-8345 2412);
FORCEPROP 1 LASTPIN (-8350 2250) $PN 2
J 0
(-8345 2260);
DISPLAY 0.489362 (-8345 2260);
PAINT MONO (-8345 2260);
FORCEPROP 1 LAST WATTAGE 1/16W
J 0
(-8300 2375);
DISPLAY 0.489362 (-8300 2375);
PAINT SKYBLUE (-8300 2375);
FORCEPROP 1 LAST MATERIAL EMPTY
J 0
(-8300 2350);
DISPLAY 0.489362 (-8300 2350);
PAINT RED (-8300 2350);
FORCEPROP 1 LAST TOLERANCE 5%
J 0
(-8300 2400);
DISPLAY 0.489362 (-8300 2400);
PAINT SKYBLUE (-8300 2400);
FORCEPROP 1 LAST VALUE 1K
J 0
(-8305 2425);
DISPLAY 0.489362 (-8305 2425);
PAINT SKYBLUE (-8305 2425);
FORCEPROP 1 LAST PACK_TYPE 0402LF
J 0
(-8300 2300);
DISPLAY 0.489362 (-8300 2300);
PAINT SKYBLUE (-8300 2300);
FORCEPROP 2 LAST BOM_COST MEM
J 0
(-8300 2525);
DISPLAY 0.808511 (-8300 2525);
DISPLAY INVISIBLE (-8300 2525);
FORCEPROP 2 LAST CDS_LIB pure_quanta
J 0
(-8350 2350);
DISPLAY INVISIBLE (-8350 2350);
FORCEPROP 1 LAST PATH I189
J 0
(-8300 2525);
DISPLAY 0.978723 (-8300 2525);
PAINT WHITE (-8300 2525);
DISPLAY INVISIBLE (-8300 2525);
FORCEPROP 1 LAST PART_NUMBER TMP_QCS21002JB34
J 0
(-8300 2325);
DISPLAY 0.489362 (-8300 2325);
PAINT SKYBLUE (-8300 2325);
DISPLAY INVISIBLE (-8300 2325);
FORCEPROP 2 LAST ROOM MEM_CH_A_CPU0_DIMM1
J 0
(-8300 2575);
DISPLAY 0.808511 (-8300 2575);
PAINT RED (-8300 2575);
DISPLAY INVISIBLE (-8300 2575);
FORCEADD OFFPAGE..1
(-8300 4650);
FORCEPROP 2 LAST $XR0 18 
J 0
(-8521 4650);
DISPLAY 0.638298 (-8521 4650);
PAINT MONO (-8521 4650);
FORCEPROP 2 LAST PATH I19
J 0
(-8250 4725);
DISPLAY 1.021277 (-8250 4725);
DISPLAY INVISIBLE (-8250 4725);
FORCEPROP 1 LAST COMMENT_BODY TRUE
J 0
(-8175 4550);
DISPLAY 0.872340 (-8175 4550);
PAINT GREEN (-8175 4550);
DISPLAY INVISIBLE (-8175 4550);
FORCEPROP 1 LAST OFFPAGE TRUE
J 0
(-7975 4525);
DISPLAY 0.872340 (-7975 4525);
PAINT GREEN (-7975 4525);
DISPLAY INVISIBLE (-7975 4525);
FORCEPROP 2 LAST CDS_LIB mstr_standard
J 0
(-8300 4650);
DISPLAY 0.723404 (-8300 4650);
PAINT MONO (-8300 4650);
DISPLAY INVISIBLE (-8300 4650);
FORCEADD VCC_CORE..1
(-8350 2525);
FORCEPROP 3 LASTPIN (-8350 2475) SIG_NAME P3V3_STBY\g
J 0
(-8340 2485);
DISPLAY 0.659574 (-8340 2485);
PAINT MONO (-8340 2485);
DISPLAY INVISIBLE (-8340 2485);
FORCEPROP 1 LAST HDL_POWER P3V3_STBY
J 1
(-8350 2575);
DISPLAY 0.489362 (-8350 2575);
PAINT GREEN (-8350 2575);
FORCEPROP 2 LAST CDS_LIB mstr_symbols
J 0
(-8350 2525);
DISPLAY INVISIBLE (-8350 2525);
FORCEPROP 1 LAST PATH I190
J 0
(-8300 2550);
DISPLAY 0.872340 (-8300 2550);
PAINT AQUA (-8300 2550);
DISPLAY INVISIBLE (-8300 2550);
FORCEPROP 0 LAST VOLTAGE 3.3
J 0
(-8625 2675);
DISPLAY 1.021277 (-8625 2675);
PAINT SKYBLUE (-8625 2675);
DISPLAY INVISIBLE (-8625 2675);
FORCEPROP 2 LAST ROOM PVCCINFAON_CPU0_CTRL
J 0
(-8350 2625);
DISPLAY 0.808511 (-8350 2625);
PAINT RED (-8350 2625);
DISPLAY INVISIBLE (-8350 2625);
FORCEADD TAP..1
(-3450 4100);
FORCEPROP 3 LASTPIN (-3500 4100) SIG_NAME M_I_CPU0_SA_DQS_DP<5>
J 0
(-3490 4110);
DISPLAY 0.659574 (-3490 4110);
PAINT MONO (-3490 4110);
DISPLAY INVISIBLE (-3490 4110);
FORCEPROP 1 LASTPIN (-3500 4100) BN 5
J 0
(-3512 4108);
DISPLAY 0.489362 (-3512 4108);
PAINT GREEN (-3512 4108);
FORCEPROP 2 LAST CDS_LIB mstr_standard
J 0
(-3450 4100);
DISPLAY 0.723404 (-3450 4100);
PAINT MONO (-3450 4100);
DISPLAY INVISIBLE (-3450 4100);
FORCEPROP 1 LAST BODY_TYPE PLUMBING
J 0
(-3450 4150);
DISPLAY 0.872340 (-3450 4150);
PAINT GREEN (-3450 4150);
DISPLAY INVISIBLE (-3450 4150);
FORCEPROP 1 LAST HDL_TAP TRUE
J 0
(-3125 3975);
DISPLAY 0.872340 (-3125 3975);
DISPLAY INVISIBLE (-3125 3975);
FORCEPROP 1 LAST PATH I191
J 0
(-3452 4100);
DISPLAY 0.872340 (-3452 4100);
PAINT GREEN (-3452 4100);
DISPLAY INVISIBLE (-3452 4100);
FORCEADD OFFPAGE..2
(-2450 4550);
FORCEPROP 2 LAST $XR0 18 
J 0
(-2261 4550);
DISPLAY 0.638298 (-2261 4550);
PAINT MONO (-2261 4550);
FORCEPROP 1 LAST COMMENT_BODY TRUE
J 0
(-2495 4455);
DISPLAY 0.872340 (-2495 4455);
PAINT GREEN (-2495 4455);
DISPLAY INVISIBLE (-2495 4455);
FORCEPROP 1 LAST OFFPAGE TRUE
J 0
(-2125 4425);
DISPLAY 0.723404 (-2125 4425);
PAINT GREEN (-2125 4425);
DISPLAY INVISIBLE (-2125 4425);
FORCEPROP 2 LAST CDS_LIB mstr_standard
J 0
(-2450 4550);
DISPLAY 0.723404 (-2450 4550);
PAINT MONO (-2450 4550);
DISPLAY INVISIBLE (-2450 4550);
FORCEPROP 2 LAST PATH I193
J 0
(-2250 4600);
DISPLAY 0.680851 (-2250 4600);
DISPLAY INVISIBLE (-2250 4600);
FORCEADD OFFPAGE..2
(-2450 4500);
FORCEPROP 2 LAST $XR0 18 
J 0
(-2261 4500);
DISPLAY 0.638298 (-2261 4500);
PAINT MONO (-2261 4500);
FORCEPROP 1 LAST COMMENT_BODY TRUE
J 0
(-2495 4405);
DISPLAY 0.872340 (-2495 4405);
PAINT GREEN (-2495 4405);
DISPLAY INVISIBLE (-2495 4405);
FORCEPROP 1 LAST OFFPAGE TRUE
J 0
(-2125 4375);
DISPLAY 0.723404 (-2125 4375);
PAINT GREEN (-2125 4375);
DISPLAY INVISIBLE (-2125 4375);
FORCEPROP 2 LAST CDS_LIB mstr_standard
J 0
(-2450 4500);
DISPLAY 0.723404 (-2450 4500);
PAINT MONO (-2450 4500);
DISPLAY INVISIBLE (-2450 4500);
FORCEPROP 2 LAST PATH I194
J 0
(-2250 4550);
DISPLAY 0.680851 (-2250 4550);
DISPLAY INVISIBLE (-2250 4550);
FORCEADD OFFPAGE..2
(-2450 3500);
FORCEPROP 2 LAST $XR0 18 
J 0
(-2261 3500);
DISPLAY 0.638298 (-2261 3500);
PAINT MONO (-2261 3500);
FORCEPROP 1 LAST COMMENT_BODY TRUE
J 0
(-2495 3405);
DISPLAY 0.872340 (-2495 3405);
PAINT GREEN (-2495 3405);
DISPLAY INVISIBLE (-2495 3405);
FORCEPROP 1 LAST OFFPAGE TRUE
J 0
(-2125 3375);
DISPLAY 0.723404 (-2125 3375);
PAINT GREEN (-2125 3375);
DISPLAY INVISIBLE (-2125 3375);
FORCEPROP 2 LAST CDS_LIB mstr_standard
J 0
(-2450 3500);
DISPLAY 0.723404 (-2450 3500);
PAINT MONO (-2450 3500);
DISPLAY INVISIBLE (-2450 3500);
FORCEPROP 2 LAST PATH I195
J 0
(-2250 3550);
DISPLAY 0.680851 (-2250 3550);
DISPLAY INVISIBLE (-2250 3550);
FORCEADD OFFPAGE..2
(-2450 3450);
FORCEPROP 2 LAST $XR0 18 
J 0
(-2261 3450);
DISPLAY 0.638298 (-2261 3450);
PAINT MONO (-2261 3450);
FORCEPROP 1 LAST COMMENT_BODY TRUE
J 0
(-2495 3355);
DISPLAY 0.872340 (-2495 3355);
PAINT GREEN (-2495 3355);
DISPLAY INVISIBLE (-2495 3355);
FORCEPROP 1 LAST OFFPAGE TRUE
J 0
(-2125 3325);
DISPLAY 0.723404 (-2125 3325);
PAINT GREEN (-2125 3325);
DISPLAY INVISIBLE (-2125 3325);
FORCEPROP 2 LAST CDS_LIB mstr_standard
J 0
(-2450 3450);
DISPLAY 0.723404 (-2450 3450);
PAINT MONO (-2450 3450);
DISPLAY INVISIBLE (-2450 3450);
FORCEPROP 2 LAST PATH I196
J 0
(-2250 3500);
DISPLAY 0.680851 (-2250 3500);
DISPLAY INVISIBLE (-2250 3500);
FORCEADD TAP..1
(-3250 4450);
FORCEPROP 3 LASTPIN (-3300 4450) SIG_NAME M_I_CPU0_SA_DQS_DN<9>
J 0
(-3290 4460);
DISPLAY 0.659574 (-3290 4460);
PAINT MONO (-3290 4460);
DISPLAY INVISIBLE (-3290 4460);
FORCEPROP 1 LASTPIN (-3300 4450) BN 9
J 0
(-3312 4458);
DISPLAY 0.489362 (-3312 4458);
PAINT GREEN (-3312 4458);
FORCEPROP 2 LAST CDS_LIB mstr_standard
J 0
(-3250 4450);
DISPLAY 0.723404 (-3250 4450);
PAINT MONO (-3250 4450);
DISPLAY INVISIBLE (-3250 4450);
FORCEPROP 1 LAST BODY_TYPE PLUMBING
J 0
(-3250 4500);
DISPLAY 0.872340 (-3250 4500);
PAINT GREEN (-3250 4500);
DISPLAY INVISIBLE (-3250 4500);
FORCEPROP 1 LAST HDL_TAP TRUE
J 0
(-2925 4325);
DISPLAY 0.872340 (-2925 4325);
DISPLAY INVISIBLE (-2925 4325);
FORCEPROP 1 LAST PATH I197
J 0
(-3252 4450);
DISPLAY 0.872340 (-3252 4450);
PAINT GREEN (-3252 4450);
DISPLAY INVISIBLE (-3252 4450);
FORCEADD TAP..1
(-3250 4350);
FORCEPROP 3 LASTPIN (-3300 4350) SIG_NAME M_I_CPU0_SA_DQS_DN<8>
J 0
(-3290 4360);
DISPLAY 0.659574 (-3290 4360);
PAINT MONO (-3290 4360);
DISPLAY INVISIBLE (-3290 4360);
FORCEPROP 1 LASTPIN (-3300 4350) BN 8
J 0
(-3312 4358);
DISPLAY 0.489362 (-3312 4358);
PAINT GREEN (-3312 4358);
FORCEPROP 2 LAST CDS_LIB mstr_standard
J 0
(-3250 4350);
DISPLAY 0.723404 (-3250 4350);
PAINT MONO (-3250 4350);
DISPLAY INVISIBLE (-3250 4350);
FORCEPROP 1 LAST BODY_TYPE PLUMBING
J 0
(-3250 4400);
DISPLAY 0.872340 (-3250 4400);
PAINT GREEN (-3250 4400);
DISPLAY INVISIBLE (-3250 4400);
FORCEPROP 1 LAST HDL_TAP TRUE
J 0
(-2925 4225);
DISPLAY 0.872340 (-2925 4225);
DISPLAY INVISIBLE (-2925 4225);
FORCEPROP 1 LAST PATH I198
J 0
(-3252 4350);
DISPLAY 0.872340 (-3252 4350);
PAINT GREEN (-3252 4350);
DISPLAY INVISIBLE (-3252 4350);
FORCEADD TAP..1
(-3450 4400);
FORCEPROP 3 LASTPIN (-3500 4400) SIG_NAME M_I_CPU0_SA_DQS_DP<8>
J 0
(-3490 4410);
DISPLAY 0.659574 (-3490 4410);
PAINT MONO (-3490 4410);
DISPLAY INVISIBLE (-3490 4410);
FORCEPROP 1 LASTPIN (-3500 4400) BN 8
J 0
(-3512 4408);
DISPLAY 0.489362 (-3512 4408);
PAINT GREEN (-3512 4408);
FORCEPROP 2 LAST CDS_LIB mstr_standard
J 0
(-3450 4400);
DISPLAY 0.723404 (-3450 4400);
PAINT MONO (-3450 4400);
DISPLAY INVISIBLE (-3450 4400);
FORCEPROP 1 LAST BODY_TYPE PLUMBING
J 0
(-3450 4450);
DISPLAY 0.872340 (-3450 4450);
PAINT GREEN (-3450 4450);
DISPLAY INVISIBLE (-3450 4450);
FORCEPROP 1 LAST HDL_TAP TRUE
J 0
(-3125 4275);
DISPLAY 0.872340 (-3125 4275);
DISPLAY INVISIBLE (-3125 4275);
FORCEPROP 1 LAST PATH I199
J 0
(-3452 4400);
DISPLAY 0.872340 (-3452 4400);
PAINT GREEN (-3452 4400);
DISPLAY INVISIBLE (-3452 4400);
FORCEADD OFFPAGE..5
(-8300 2050);
FORCEPROP 2 LAST $XR0 18 
J 0
(-8554 2050);
DISPLAY 0.638298 (-8554 2050);
PAINT MONO (-8554 2050);
FORCEPROP 2 LAST PATH I2
J 0
(-8250 2125);
DISPLAY 1.021277 (-8250 2125);
DISPLAY INVISIBLE (-8250 2125);
FORCEPROP 1 LAST COMMENT_BODY TRUE
J 0
(-8200 1975);
DISPLAY 0.872340 (-8200 1975);
PAINT GREEN (-8200 1975);
DISPLAY INVISIBLE (-8200 1975);
FORCEPROP 1 LAST OFFPAGE TRUE
J 0
(-7975 1925);
DISPLAY 0.872340 (-7975 1925);
PAINT GREEN (-7975 1925);
DISPLAY INVISIBLE (-7975 1925);
FORCEPROP 2 LAST CDS_LIB mstr_standard
J 0
(-8300 2050);
DISPLAY 0.808511 (-8300 2050);
DISPLAY INVISIBLE (-8300 2050);
FORCEADD OFFPAGE..1
(-8300 5100);
FORCEPROP 2 LAST $XR0 18 
J 0
(-8521 5100);
DISPLAY 0.638298 (-8521 5100);
PAINT MONO (-8521 5100);
FORCEPROP 2 LAST PATH I20
J 0
(-8250 5175);
DISPLAY 1.021277 (-8250 5175);
DISPLAY INVISIBLE (-8250 5175);
FORCEPROP 1 LAST COMMENT_BODY TRUE
J 0
(-8175 5000);
DISPLAY 0.872340 (-8175 5000);
PAINT GREEN (-8175 5000);
DISPLAY INVISIBLE (-8175 5000);
FORCEPROP 1 LAST OFFPAGE TRUE
J 0
(-7975 4975);
DISPLAY 0.872340 (-7975 4975);
PAINT GREEN (-7975 4975);
DISPLAY INVISIBLE (-7975 4975);
FORCEPROP 2 LAST CDS_LIB mstr_standard
J 0
(-8300 5100);
DISPLAY 0.723404 (-8300 5100);
PAINT MONO (-8300 5100);
DISPLAY INVISIBLE (-8300 5100);
FORCEADD TAP..1
(-3450 4500);
FORCEPROP 3 LASTPIN (-3500 4500) SIG_NAME M_I_CPU0_SA_DQS_DP<9>
J 0
(-3490 4510);
DISPLAY 0.659574 (-3490 4510);
PAINT MONO (-3490 4510);
DISPLAY INVISIBLE (-3490 4510);
FORCEPROP 1 LASTPIN (-3500 4500) BN 9
J 0
(-3512 4508);
DISPLAY 0.489362 (-3512 4508);
PAINT GREEN (-3512 4508);
FORCEPROP 2 LAST CDS_LIB mstr_standard
J 0
(-3450 4500);
DISPLAY 0.723404 (-3450 4500);
PAINT MONO (-3450 4500);
DISPLAY INVISIBLE (-3450 4500);
FORCEPROP 1 LAST BODY_TYPE PLUMBING
J 0
(-3450 4550);
DISPLAY 0.872340 (-3450 4550);
PAINT GREEN (-3450 4550);
DISPLAY INVISIBLE (-3450 4550);
FORCEPROP 1 LAST HDL_TAP TRUE
J 0
(-3125 4375);
DISPLAY 0.872340 (-3125 4375);
DISPLAY INVISIBLE (-3125 4375);
FORCEPROP 1 LAST PATH I200
J 0
(-3452 4500);
DISPLAY 0.872340 (-3452 4500);
PAINT GREEN (-3452 4500);
DISPLAY INVISIBLE (-3452 4500);
FORCEADD TAP..1
(-3250 4250);
FORCEPROP 3 LASTPIN (-3300 4250) SIG_NAME M_I_CPU0_SA_DQS_DN<7>
J 0
(-3290 4260);
DISPLAY 0.659574 (-3290 4260);
PAINT MONO (-3290 4260);
DISPLAY INVISIBLE (-3290 4260);
FORCEPROP 1 LASTPIN (-3300 4250) BN 7
J 0
(-3312 4258);
DISPLAY 0.489362 (-3312 4258);
PAINT GREEN (-3312 4258);
FORCEPROP 2 LAST CDS_LIB mstr_standard
J 0
(-3250 4250);
DISPLAY 0.723404 (-3250 4250);
PAINT MONO (-3250 4250);
DISPLAY INVISIBLE (-3250 4250);
FORCEPROP 1 LAST BODY_TYPE PLUMBING
J 0
(-3250 4300);
DISPLAY 0.872340 (-3250 4300);
PAINT GREEN (-3250 4300);
DISPLAY INVISIBLE (-3250 4300);
FORCEPROP 1 LAST HDL_TAP TRUE
J 0
(-2925 4125);
DISPLAY 0.872340 (-2925 4125);
DISPLAY INVISIBLE (-2925 4125);
FORCEPROP 1 LAST PATH I201
J 0
(-3252 4250);
DISPLAY 0.872340 (-3252 4250);
PAINT GREEN (-3252 4250);
DISPLAY INVISIBLE (-3252 4250);
FORCEADD TAP..1
(-3250 4150);
FORCEPROP 3 LASTPIN (-3300 4150) SIG_NAME M_I_CPU0_SA_DQS_DN<6>
J 0
(-3290 4160);
DISPLAY 0.659574 (-3290 4160);
PAINT MONO (-3290 4160);
DISPLAY INVISIBLE (-3290 4160);
FORCEPROP 1 LASTPIN (-3300 4150) BN 6
J 0
(-3312 4158);
DISPLAY 0.489362 (-3312 4158);
PAINT GREEN (-3312 4158);
FORCEPROP 2 LAST CDS_LIB mstr_standard
J 0
(-3250 4150);
DISPLAY 0.723404 (-3250 4150);
PAINT MONO (-3250 4150);
DISPLAY INVISIBLE (-3250 4150);
FORCEPROP 1 LAST BODY_TYPE PLUMBING
J 0
(-3250 4200);
DISPLAY 0.872340 (-3250 4200);
PAINT GREEN (-3250 4200);
DISPLAY INVISIBLE (-3250 4200);
FORCEPROP 1 LAST HDL_TAP TRUE
J 0
(-2925 4025);
DISPLAY 0.872340 (-2925 4025);
DISPLAY INVISIBLE (-2925 4025);
FORCEPROP 1 LAST PATH I202
J 0
(-3252 4150);
DISPLAY 0.872340 (-3252 4150);
PAINT GREEN (-3252 4150);
DISPLAY INVISIBLE (-3252 4150);
FORCEADD TAP..1
(-3250 4050);
FORCEPROP 3 LASTPIN (-3300 4050) SIG_NAME M_I_CPU0_SA_DQS_DN<5>
J 0
(-3290 4060);
DISPLAY 0.659574 (-3290 4060);
PAINT MONO (-3290 4060);
DISPLAY INVISIBLE (-3290 4060);
FORCEPROP 1 LASTPIN (-3300 4050) BN 5
J 0
(-3312 4058);
DISPLAY 0.489362 (-3312 4058);
PAINT GREEN (-3312 4058);
FORCEPROP 2 LAST CDS_LIB mstr_standard
J 0
(-3250 4050);
DISPLAY 0.723404 (-3250 4050);
PAINT MONO (-3250 4050);
DISPLAY INVISIBLE (-3250 4050);
FORCEPROP 1 LAST BODY_TYPE PLUMBING
J 0
(-3250 4100);
DISPLAY 0.872340 (-3250 4100);
PAINT GREEN (-3250 4100);
DISPLAY INVISIBLE (-3250 4100);
FORCEPROP 1 LAST HDL_TAP TRUE
J 0
(-2925 3925);
DISPLAY 0.872340 (-2925 3925);
DISPLAY INVISIBLE (-2925 3925);
FORCEPROP 1 LAST PATH I203
J 0
(-3252 4050);
DISPLAY 0.872340 (-3252 4050);
PAINT GREEN (-3252 4050);
DISPLAY INVISIBLE (-3252 4050);
FORCEADD TAP..1
(-3250 3950);
FORCEPROP 3 LASTPIN (-3300 3950) SIG_NAME M_I_CPU0_SA_DQS_DN<4>
J 0
(-3290 3960);
DISPLAY 0.659574 (-3290 3960);
PAINT MONO (-3290 3960);
DISPLAY INVISIBLE (-3290 3960);
FORCEPROP 1 LASTPIN (-3300 3950) BN 4
J 0
(-3312 3958);
DISPLAY 0.489362 (-3312 3958);
PAINT GREEN (-3312 3958);
FORCEPROP 2 LAST CDS_LIB mstr_standard
J 0
(-3250 3950);
DISPLAY 0.723404 (-3250 3950);
PAINT MONO (-3250 3950);
DISPLAY INVISIBLE (-3250 3950);
FORCEPROP 1 LAST BODY_TYPE PLUMBING
J 0
(-3250 4000);
DISPLAY 0.872340 (-3250 4000);
PAINT GREEN (-3250 4000);
DISPLAY INVISIBLE (-3250 4000);
FORCEPROP 1 LAST HDL_TAP TRUE
J 0
(-2925 3825);
DISPLAY 0.872340 (-2925 3825);
DISPLAY INVISIBLE (-2925 3825);
FORCEPROP 1 LAST PATH I204
J 0
(-3252 3950);
DISPLAY 0.872340 (-3252 3950);
PAINT GREEN (-3252 3950);
DISPLAY INVISIBLE (-3252 3950);
FORCEADD TAP..1
(-3250 3850);
FORCEPROP 3 LASTPIN (-3300 3850) SIG_NAME M_I_CPU0_SA_DQS_DN<3>
J 0
(-3290 3860);
DISPLAY 0.659574 (-3290 3860);
PAINT MONO (-3290 3860);
DISPLAY INVISIBLE (-3290 3860);
FORCEPROP 1 LASTPIN (-3300 3850) BN 3
J 0
(-3312 3858);
DISPLAY 0.489362 (-3312 3858);
PAINT GREEN (-3312 3858);
FORCEPROP 2 LAST CDS_LIB mstr_standard
J 0
(-3250 3850);
DISPLAY 0.723404 (-3250 3850);
PAINT MONO (-3250 3850);
DISPLAY INVISIBLE (-3250 3850);
FORCEPROP 1 LAST BODY_TYPE PLUMBING
J 0
(-3250 3900);
DISPLAY 0.872340 (-3250 3900);
PAINT GREEN (-3250 3900);
DISPLAY INVISIBLE (-3250 3900);
FORCEPROP 1 LAST HDL_TAP TRUE
J 0
(-2925 3725);
DISPLAY 0.872340 (-2925 3725);
DISPLAY INVISIBLE (-2925 3725);
FORCEPROP 1 LAST PATH I205
J 0
(-3252 3850);
DISPLAY 0.872340 (-3252 3850);
PAINT GREEN (-3252 3850);
DISPLAY INVISIBLE (-3252 3850);
FORCEADD TAP..1
(-3250 3750);
FORCEPROP 3 LASTPIN (-3300 3750) SIG_NAME M_I_CPU0_SA_DQS_DN<2>
J 0
(-3290 3760);
DISPLAY 0.659574 (-3290 3760);
PAINT MONO (-3290 3760);
DISPLAY INVISIBLE (-3290 3760);
FORCEPROP 1 LASTPIN (-3300 3750) BN 2
J 0
(-3312 3758);
DISPLAY 0.489362 (-3312 3758);
PAINT GREEN (-3312 3758);
FORCEPROP 2 LAST CDS_LIB mstr_standard
J 0
(-3250 3750);
DISPLAY 0.723404 (-3250 3750);
PAINT MONO (-3250 3750);
DISPLAY INVISIBLE (-3250 3750);
FORCEPROP 1 LAST BODY_TYPE PLUMBING
J 0
(-3250 3800);
DISPLAY 0.872340 (-3250 3800);
PAINT GREEN (-3250 3800);
DISPLAY INVISIBLE (-3250 3800);
FORCEPROP 1 LAST HDL_TAP TRUE
J 0
(-2925 3625);
DISPLAY 0.872340 (-2925 3625);
DISPLAY INVISIBLE (-2925 3625);
FORCEPROP 1 LAST PATH I206
J 0
(-3252 3750);
DISPLAY 0.872340 (-3252 3750);
PAINT GREEN (-3252 3750);
DISPLAY INVISIBLE (-3252 3750);
FORCEADD TAP..1
(-3250 3650);
FORCEPROP 3 LASTPIN (-3300 3650) SIG_NAME M_I_CPU0_SA_DQS_DN<1>
J 0
(-3290 3660);
DISPLAY 0.659574 (-3290 3660);
PAINT MONO (-3290 3660);
DISPLAY INVISIBLE (-3290 3660);
FORCEPROP 1 LASTPIN (-3300 3650) BN 1
J 0
(-3312 3658);
DISPLAY 0.489362 (-3312 3658);
PAINT GREEN (-3312 3658);
FORCEPROP 2 LAST CDS_LIB mstr_standard
J 0
(-3250 3650);
DISPLAY 0.723404 (-3250 3650);
PAINT MONO (-3250 3650);
DISPLAY INVISIBLE (-3250 3650);
FORCEPROP 1 LAST BODY_TYPE PLUMBING
J 0
(-3250 3700);
DISPLAY 0.872340 (-3250 3700);
PAINT GREEN (-3250 3700);
DISPLAY INVISIBLE (-3250 3700);
FORCEPROP 1 LAST HDL_TAP TRUE
J 0
(-2925 3525);
DISPLAY 0.872340 (-2925 3525);
DISPLAY INVISIBLE (-2925 3525);
FORCEPROP 1 LAST PATH I207
J 0
(-3252 3650);
DISPLAY 0.872340 (-3252 3650);
PAINT GREEN (-3252 3650);
DISPLAY INVISIBLE (-3252 3650);
FORCEADD TAP..1
(-3250 3400);
FORCEPROP 3 LASTPIN (-3300 3400) SIG_NAME M_I_CPU0_SB_DQS_DN<9>
J 0
(-3290 3410);
DISPLAY 0.659574 (-3290 3410);
PAINT MONO (-3290 3410);
DISPLAY INVISIBLE (-3290 3410);
FORCEPROP 1 LASTPIN (-3300 3400) BN 9
J 0
(-3312 3408);
DISPLAY 0.489362 (-3312 3408);
PAINT GREEN (-3312 3408);
FORCEPROP 2 LAST CDS_LIB mstr_standard
J 0
(-3250 3400);
DISPLAY 0.723404 (-3250 3400);
PAINT MONO (-3250 3400);
DISPLAY INVISIBLE (-3250 3400);
FORCEPROP 1 LAST BODY_TYPE PLUMBING
J 0
(-3250 3450);
DISPLAY 0.872340 (-3250 3450);
PAINT GREEN (-3250 3450);
DISPLAY INVISIBLE (-3250 3450);
FORCEPROP 1 LAST HDL_TAP TRUE
J 0
(-2925 3275);
DISPLAY 0.872340 (-2925 3275);
DISPLAY INVISIBLE (-2925 3275);
FORCEPROP 1 LAST PATH I208
J 0
(-3252 3400);
DISPLAY 0.872340 (-3252 3400);
PAINT GREEN (-3252 3400);
DISPLAY INVISIBLE (-3252 3400);
FORCEADD TAP..1
(-3250 3550);
FORCEPROP 3 LASTPIN (-3300 3550) SIG_NAME M_I_CPU0_SA_DQS_DN<0>
J 0
(-3290 3560);
DISPLAY 0.659574 (-3290 3560);
PAINT MONO (-3290 3560);
DISPLAY INVISIBLE (-3290 3560);
FORCEPROP 1 LASTPIN (-3300 3550) BN 0
J 0
(-3312 3558);
DISPLAY 0.489362 (-3312 3558);
PAINT GREEN (-3312 3558);
FORCEPROP 2 LAST CDS_LIB mstr_standard
J 0
(-3250 3550);
DISPLAY 0.723404 (-3250 3550);
PAINT MONO (-3250 3550);
DISPLAY INVISIBLE (-3250 3550);
FORCEPROP 1 LAST BODY_TYPE PLUMBING
J 0
(-3250 3600);
DISPLAY 0.872340 (-3250 3600);
PAINT GREEN (-3250 3600);
DISPLAY INVISIBLE (-3250 3600);
FORCEPROP 1 LAST HDL_TAP TRUE
J 0
(-2925 3425);
DISPLAY 0.872340 (-2925 3425);
DISPLAY INVISIBLE (-2925 3425);
FORCEPROP 1 LAST PATH I209
J 0
(-3252 3550);
DISPLAY 0.872340 (-3252 3550);
PAINT GREEN (-3252 3550);
DISPLAY INVISIBLE (-3252 3550);
FORCEADD OFFPAGE..1
(-8300 5500);
FORCEPROP 2 LAST $XR0 18 
J 0
(-8521 5500);
DISPLAY 0.638298 (-8521 5500);
PAINT MONO (-8521 5500);
FORCEPROP 2 LAST PATH I21
J 0
(-8250 5575);
DISPLAY 1.021277 (-8250 5575);
DISPLAY INVISIBLE (-8250 5575);
FORCEPROP 1 LAST COMMENT_BODY TRUE
J 0
(-8175 5400);
DISPLAY 0.872340 (-8175 5400);
PAINT GREEN (-8175 5400);
DISPLAY INVISIBLE (-8175 5400);
FORCEPROP 1 LAST OFFPAGE TRUE
J 0
(-7975 5375);
DISPLAY 0.872340 (-7975 5375);
PAINT GREEN (-7975 5375);
DISPLAY INVISIBLE (-7975 5375);
FORCEPROP 2 LAST CDS_LIB mstr_standard
J 0
(-8300 5500);
DISPLAY 0.723404 (-8300 5500);
PAINT MONO (-8300 5500);
DISPLAY INVISIBLE (-8300 5500);
FORCEADD TAP..1
(-3450 4300);
FORCEPROP 3 LASTPIN (-3500 4300) SIG_NAME M_I_CPU0_SA_DQS_DP<7>
J 0
(-3490 4310);
DISPLAY 0.659574 (-3490 4310);
PAINT MONO (-3490 4310);
DISPLAY INVISIBLE (-3490 4310);
FORCEPROP 1 LASTPIN (-3500 4300) BN 7
J 0
(-3512 4308);
DISPLAY 0.489362 (-3512 4308);
PAINT GREEN (-3512 4308);
FORCEPROP 2 LAST CDS_LIB mstr_standard
J 0
(-3450 4300);
DISPLAY 0.723404 (-3450 4300);
PAINT MONO (-3450 4300);
DISPLAY INVISIBLE (-3450 4300);
FORCEPROP 1 LAST BODY_TYPE PLUMBING
J 0
(-3450 4350);
DISPLAY 0.872340 (-3450 4350);
PAINT GREEN (-3450 4350);
DISPLAY INVISIBLE (-3450 4350);
FORCEPROP 1 LAST HDL_TAP TRUE
J 0
(-3125 4175);
DISPLAY 0.872340 (-3125 4175);
DISPLAY INVISIBLE (-3125 4175);
FORCEPROP 1 LAST PATH I210
J 0
(-3452 4300);
DISPLAY 0.872340 (-3452 4300);
PAINT GREEN (-3452 4300);
DISPLAY INVISIBLE (-3452 4300);
FORCEADD TAP..1
(-3450 4200);
FORCEPROP 3 LASTPIN (-3500 4200) SIG_NAME M_I_CPU0_SA_DQS_DP<6>
J 0
(-3490 4210);
DISPLAY 0.659574 (-3490 4210);
PAINT MONO (-3490 4210);
DISPLAY INVISIBLE (-3490 4210);
FORCEPROP 1 LASTPIN (-3500 4200) BN 6
J 0
(-3512 4208);
DISPLAY 0.489362 (-3512 4208);
PAINT GREEN (-3512 4208);
FORCEPROP 2 LAST CDS_LIB mstr_standard
J 0
(-3450 4200);
DISPLAY 0.723404 (-3450 4200);
PAINT MONO (-3450 4200);
DISPLAY INVISIBLE (-3450 4200);
FORCEPROP 1 LAST BODY_TYPE PLUMBING
J 0
(-3450 4250);
DISPLAY 0.872340 (-3450 4250);
PAINT GREEN (-3450 4250);
DISPLAY INVISIBLE (-3450 4250);
FORCEPROP 1 LAST HDL_TAP TRUE
J 0
(-3125 4075);
DISPLAY 0.872340 (-3125 4075);
DISPLAY INVISIBLE (-3125 4075);
FORCEPROP 1 LAST PATH I211
J 0
(-3452 4200);
DISPLAY 0.872340 (-3452 4200);
PAINT GREEN (-3452 4200);
DISPLAY INVISIBLE (-3452 4200);
FORCEADD TAP..1
(-3450 4000);
FORCEPROP 3 LASTPIN (-3500 4000) SIG_NAME M_I_CPU0_SA_DQS_DP<4>
J 0
(-3490 4010);
DISPLAY 0.659574 (-3490 4010);
PAINT MONO (-3490 4010);
DISPLAY INVISIBLE (-3490 4010);
FORCEPROP 1 LASTPIN (-3500 4000) BN 4
J 0
(-3512 4008);
DISPLAY 0.489362 (-3512 4008);
PAINT GREEN (-3512 4008);
FORCEPROP 2 LAST CDS_LIB mstr_standard
J 0
(-3450 4000);
DISPLAY 0.723404 (-3450 4000);
PAINT MONO (-3450 4000);
DISPLAY INVISIBLE (-3450 4000);
FORCEPROP 1 LAST BODY_TYPE PLUMBING
J 0
(-3450 4050);
DISPLAY 0.872340 (-3450 4050);
PAINT GREEN (-3450 4050);
DISPLAY INVISIBLE (-3450 4050);
FORCEPROP 1 LAST HDL_TAP TRUE
J 0
(-3125 3875);
DISPLAY 0.872340 (-3125 3875);
DISPLAY INVISIBLE (-3125 3875);
FORCEPROP 1 LAST PATH I212
J 0
(-3452 4000);
DISPLAY 0.872340 (-3452 4000);
PAINT GREEN (-3452 4000);
DISPLAY INVISIBLE (-3452 4000);
FORCEADD TAP..1
(-3450 3900);
FORCEPROP 3 LASTPIN (-3500 3900) SIG_NAME M_I_CPU0_SA_DQS_DP<3>
J 0
(-3490 3910);
DISPLAY 0.659574 (-3490 3910);
PAINT MONO (-3490 3910);
DISPLAY INVISIBLE (-3490 3910);
FORCEPROP 1 LASTPIN (-3500 3900) BN 3
J 0
(-3512 3908);
DISPLAY 0.489362 (-3512 3908);
PAINT GREEN (-3512 3908);
FORCEPROP 2 LAST CDS_LIB mstr_standard
J 0
(-3450 3900);
DISPLAY 0.723404 (-3450 3900);
PAINT MONO (-3450 3900);
DISPLAY INVISIBLE (-3450 3900);
FORCEPROP 1 LAST BODY_TYPE PLUMBING
J 0
(-3450 3950);
DISPLAY 0.872340 (-3450 3950);
PAINT GREEN (-3450 3950);
DISPLAY INVISIBLE (-3450 3950);
FORCEPROP 1 LAST HDL_TAP TRUE
J 0
(-3125 3775);
DISPLAY 0.872340 (-3125 3775);
DISPLAY INVISIBLE (-3125 3775);
FORCEPROP 1 LAST PATH I213
J 0
(-3452 3900);
DISPLAY 0.872340 (-3452 3900);
PAINT GREEN (-3452 3900);
DISPLAY INVISIBLE (-3452 3900);
FORCEADD TAP..1
(-3450 3700);
FORCEPROP 3 LASTPIN (-3500 3700) SIG_NAME M_I_CPU0_SA_DQS_DP<1>
J 0
(-3490 3710);
DISPLAY 0.659574 (-3490 3710);
PAINT MONO (-3490 3710);
DISPLAY INVISIBLE (-3490 3710);
FORCEPROP 1 LASTPIN (-3500 3700) BN 1
J 0
(-3512 3708);
DISPLAY 0.489362 (-3512 3708);
PAINT GREEN (-3512 3708);
FORCEPROP 2 LAST CDS_LIB mstr_standard
J 0
(-3450 3700);
DISPLAY 0.723404 (-3450 3700);
PAINT MONO (-3450 3700);
DISPLAY INVISIBLE (-3450 3700);
FORCEPROP 1 LAST BODY_TYPE PLUMBING
J 0
(-3450 3750);
DISPLAY 0.872340 (-3450 3750);
PAINT GREEN (-3450 3750);
DISPLAY INVISIBLE (-3450 3750);
FORCEPROP 1 LAST HDL_TAP TRUE
J 0
(-3125 3575);
DISPLAY 0.872340 (-3125 3575);
DISPLAY INVISIBLE (-3125 3575);
FORCEPROP 1 LAST PATH I214
J 0
(-3452 3700);
DISPLAY 0.872340 (-3452 3700);
PAINT GREEN (-3452 3700);
DISPLAY INVISIBLE (-3452 3700);
FORCEADD TAP..1
(-3450 3800);
FORCEPROP 3 LASTPIN (-3500 3800) SIG_NAME M_I_CPU0_SA_DQS_DP<2>
J 0
(-3490 3810);
DISPLAY 0.659574 (-3490 3810);
PAINT MONO (-3490 3810);
DISPLAY INVISIBLE (-3490 3810);
FORCEPROP 1 LASTPIN (-3500 3800) BN 2
J 0
(-3512 3808);
DISPLAY 0.489362 (-3512 3808);
PAINT GREEN (-3512 3808);
FORCEPROP 2 LAST CDS_LIB mstr_standard
J 0
(-3450 3800);
DISPLAY 0.723404 (-3450 3800);
PAINT MONO (-3450 3800);
DISPLAY INVISIBLE (-3450 3800);
FORCEPROP 1 LAST BODY_TYPE PLUMBING
J 0
(-3450 3850);
DISPLAY 0.872340 (-3450 3850);
PAINT GREEN (-3450 3850);
DISPLAY INVISIBLE (-3450 3850);
FORCEPROP 1 LAST HDL_TAP TRUE
J 0
(-3125 3675);
DISPLAY 0.872340 (-3125 3675);
DISPLAY INVISIBLE (-3125 3675);
FORCEPROP 1 LAST PATH I215
J 0
(-3452 3800);
DISPLAY 0.872340 (-3452 3800);
PAINT GREEN (-3452 3800);
DISPLAY INVISIBLE (-3452 3800);
FORCEADD TAP..1
(-3450 3600);
FORCEPROP 3 LASTPIN (-3500 3600) SIG_NAME M_I_CPU0_SA_DQS_DP<0>
J 0
(-3490 3610);
DISPLAY 0.659574 (-3490 3610);
PAINT MONO (-3490 3610);
DISPLAY INVISIBLE (-3490 3610);
FORCEPROP 1 LASTPIN (-3500 3600) BN 0
J 0
(-3512 3608);
DISPLAY 0.489362 (-3512 3608);
PAINT GREEN (-3512 3608);
FORCEPROP 2 LAST CDS_LIB mstr_standard
J 0
(-3450 3600);
DISPLAY 0.723404 (-3450 3600);
PAINT MONO (-3450 3600);
DISPLAY INVISIBLE (-3450 3600);
FORCEPROP 1 LAST BODY_TYPE PLUMBING
J 0
(-3450 3650);
DISPLAY 0.872340 (-3450 3650);
PAINT GREEN (-3450 3650);
DISPLAY INVISIBLE (-3450 3650);
FORCEPROP 1 LAST HDL_TAP TRUE
J 0
(-3125 3475);
DISPLAY 0.872340 (-3125 3475);
DISPLAY INVISIBLE (-3125 3475);
FORCEPROP 1 LAST PATH I216
J 0
(-3452 3600);
DISPLAY 0.872340 (-3452 3600);
PAINT GREEN (-3452 3600);
DISPLAY INVISIBLE (-3452 3600);
FORCEADD TAP..1
(-3450 3350);
FORCEPROP 3 LASTPIN (-3500 3350) SIG_NAME M_I_CPU0_SB_DQS_DP<8>
J 0
(-3490 3360);
DISPLAY 0.659574 (-3490 3360);
PAINT MONO (-3490 3360);
DISPLAY INVISIBLE (-3490 3360);
FORCEPROP 1 LASTPIN (-3500 3350) BN 8
J 0
(-3512 3358);
DISPLAY 0.489362 (-3512 3358);
PAINT GREEN (-3512 3358);
FORCEPROP 2 LAST CDS_LIB mstr_standard
J 0
(-3450 3350);
DISPLAY 0.723404 (-3450 3350);
PAINT MONO (-3450 3350);
DISPLAY INVISIBLE (-3450 3350);
FORCEPROP 1 LAST BODY_TYPE PLUMBING
J 0
(-3450 3400);
DISPLAY 0.872340 (-3450 3400);
PAINT GREEN (-3450 3400);
DISPLAY INVISIBLE (-3450 3400);
FORCEPROP 1 LAST HDL_TAP TRUE
J 0
(-3125 3225);
DISPLAY 0.872340 (-3125 3225);
DISPLAY INVISIBLE (-3125 3225);
FORCEPROP 1 LAST PATH I217
J 0
(-3452 3350);
DISPLAY 0.872340 (-3452 3350);
PAINT GREEN (-3452 3350);
DISPLAY INVISIBLE (-3452 3350);
FORCEADD TAP..1
(-3450 3450);
FORCEPROP 3 LASTPIN (-3500 3450) SIG_NAME M_I_CPU0_SB_DQS_DP<9>
J 0
(-3490 3460);
DISPLAY 0.659574 (-3490 3460);
PAINT MONO (-3490 3460);
DISPLAY INVISIBLE (-3490 3460);
FORCEPROP 1 LASTPIN (-3500 3450) BN 9
J 0
(-3512 3458);
DISPLAY 0.489362 (-3512 3458);
PAINT GREEN (-3512 3458);
FORCEPROP 2 LAST CDS_LIB mstr_standard
J 0
(-3450 3450);
DISPLAY 0.723404 (-3450 3450);
PAINT MONO (-3450 3450);
DISPLAY INVISIBLE (-3450 3450);
FORCEPROP 1 LAST BODY_TYPE PLUMBING
J 0
(-3450 3500);
DISPLAY 0.872340 (-3450 3500);
PAINT GREEN (-3450 3500);
DISPLAY INVISIBLE (-3450 3500);
FORCEPROP 1 LAST HDL_TAP TRUE
J 0
(-3125 3325);
DISPLAY 0.872340 (-3125 3325);
DISPLAY INVISIBLE (-3125 3325);
FORCEPROP 1 LAST PATH I218
J 0
(-3452 3450);
DISPLAY 0.872340 (-3452 3450);
PAINT GREEN (-3452 3450);
DISPLAY INVISIBLE (-3452 3450);
FORCEADD TAP..1
(-3250 3300);
FORCEPROP 3 LASTPIN (-3300 3300) SIG_NAME M_I_CPU0_SB_DQS_DN<8>
J 0
(-3290 3310);
DISPLAY 0.659574 (-3290 3310);
PAINT MONO (-3290 3310);
DISPLAY INVISIBLE (-3290 3310);
FORCEPROP 1 LASTPIN (-3300 3300) BN 8
J 0
(-3312 3308);
DISPLAY 0.489362 (-3312 3308);
PAINT GREEN (-3312 3308);
FORCEPROP 2 LAST CDS_LIB mstr_standard
J 0
(-3250 3300);
DISPLAY 0.723404 (-3250 3300);
PAINT MONO (-3250 3300);
DISPLAY INVISIBLE (-3250 3300);
FORCEPROP 1 LAST BODY_TYPE PLUMBING
J 0
(-3250 3350);
DISPLAY 0.872340 (-3250 3350);
PAINT GREEN (-3250 3350);
DISPLAY INVISIBLE (-3250 3350);
FORCEPROP 1 LAST HDL_TAP TRUE
J 0
(-2925 3175);
DISPLAY 0.872340 (-2925 3175);
DISPLAY INVISIBLE (-2925 3175);
FORCEPROP 1 LAST PATH I219
J 0
(-3252 3300);
DISPLAY 0.872340 (-3252 3300);
PAINT GREEN (-3252 3300);
DISPLAY INVISIBLE (-3252 3300);
FORCEADD SCONN288_DDR506112002KQ..1
(-6850 3700);
FORCEPROP 1 LAST LOCATION J18
J 0
(-7300 5775);
DISPLAY 0.468085 (-7300 5775);
PAINT SKYBLUE (-7300 5775);
FORCEPROP 0 LAST $SEC 1
J 0
(-7300 5925);
DISPLAY 0.680851 (-7300 5925);
PAINT MONO (-7300 5925);
DISPLAY INVISIBLE (-7300 5925);
FORCEPROP 2 LAST CDS_SEC 1
J 0
(-7300 5925);
DISPLAY 1.021277 (-7300 5925);
DISPLAY INVISIBLE (-7300 5925);
FORCEPROP 0 LASTPIN (-7450 3100) $PN 62
J 2
(-7460 3110);
DISPLAY 0.680851 (-7460 3110);
PAINT MONO (-7460 3110);
FORCEPROP 0 LASTPIN (-7450 5150) $PN 66
J 2
(-7460 5160);
DISPLAY 0.680851 (-7460 5160);
PAINT MONO (-7460 5160);
FORCEPROP 0 LASTPIN (-7450 4750) $PN 76
J 2
(-7460 4760);
DISPLAY 0.680851 (-7460 4760);
PAINT MONO (-7460 4760);
FORCEPROP 0 LASTPIN (-7450 5200) $PN 211
J 2
(-7460 5210);
DISPLAY 0.680851 (-7460 5210);
PAINT MONO (-7460 5210);
FORCEPROP 0 LASTPIN (-7450 4800) $PN 221
J 2
(-7460 4810);
DISPLAY 0.680851 (-7460 4810);
PAINT MONO (-7460 4810);
FORCEPROP 0 LASTPIN (-7450 5250) $PN 68
J 2
(-7460 5260);
DISPLAY 0.680851 (-7460 5260);
PAINT MONO (-7460 5260);
FORCEPROP 0 LASTPIN (-7450 4850) $PN 78
J 2
(-7460 4860);
DISPLAY 0.680851 (-7460 4860);
PAINT MONO (-7460 4860);
FORCEPROP 0 LASTPIN (-7450 5300) $PN 213
J 2
(-7460 5310);
DISPLAY 0.680851 (-7460 5310);
PAINT MONO (-7460 5310);
FORCEPROP 0 LASTPIN (-7450 4900) $PN 223
J 2
(-7460 4910);
DISPLAY 0.680851 (-7460 4910);
PAINT MONO (-7460 4910);
FORCEPROP 0 LASTPIN (-7450 5350) $PN 70
J 2
(-7460 5360);
DISPLAY 0.680851 (-7460 5360);
PAINT MONO (-7460 5360);
FORCEPROP 0 LASTPIN (-7450 4950) $PN 80
J 2
(-7460 4960);
DISPLAY 0.680851 (-7460 4960);
PAINT MONO (-7460 4960);
FORCEPROP 0 LASTPIN (-7450 5400) $PN 215
J 2
(-7460 5410);
DISPLAY 0.680851 (-7460 5410);
PAINT MONO (-7460 5410);
FORCEPROP 0 LASTPIN (-7450 5000) $PN 225
J 2
(-7460 5010);
DISPLAY 0.680851 (-7460 5010);
PAINT MONO (-7460 5010);
FORCEPROP 0 LASTPIN (-7450 5450) $PN 72
J 2
(-7460 5460);
DISPLAY 0.680851 (-7460 5460);
PAINT MONO (-7460 5460);
FORCEPROP 0 LASTPIN (-7450 5050) $PN 82
J 2
(-7460 5060);
DISPLAY 0.680851 (-7460 5060);
PAINT MONO (-7460 5060);
FORCEPROP 0 LASTPIN (-7450 3700) $PN 51
J 2
(-7460 3710);
DISPLAY 0.680851 (-7460 3710);
PAINT MONO (-7460 3710);
FORCEPROP 0 LASTPIN (-7450 3250) $PN 96
J 2
(-7460 3260);
DISPLAY 0.680851 (-7460 3260);
PAINT MONO (-7460 3260);
FORCEPROP 0 LASTPIN (-7450 3750) $PN 53
J 2
(-7460 3760);
DISPLAY 0.680851 (-7460 3760);
PAINT MONO (-7460 3760);
FORCEPROP 0 LASTPIN (-7450 3300) $PN 98
J 2
(-7460 3310);
DISPLAY 0.680851 (-7460 3310);
PAINT MONO (-7460 3310);
FORCEPROP 0 LASTPIN (-7450 3800) $PN 196
J 2
(-7460 3810);
DISPLAY 0.680851 (-7460 3810);
PAINT MONO (-7460 3810);
FORCEPROP 0 LASTPIN (-7450 3350) $PN 241
J 2
(-7460 3360);
DISPLAY 0.680851 (-7460 3360);
PAINT MONO (-7460 3360);
FORCEPROP 0 LASTPIN (-7450 3850) $PN 198
J 2
(-7460 3860);
DISPLAY 0.680851 (-7460 3860);
PAINT MONO (-7460 3860);
FORCEPROP 0 LASTPIN (-7450 3400) $PN 243
J 2
(-7460 3410);
DISPLAY 0.680851 (-7460 3410);
PAINT MONO (-7460 3410);
FORCEPROP 0 LASTPIN (-7450 3900) $PN 58
J 2
(-7460 3910);
DISPLAY 0.680851 (-7460 3910);
PAINT MONO (-7460 3910);
FORCEPROP 0 LASTPIN (-7450 3450) $PN 89
J 2
(-7460 3460);
DISPLAY 0.680851 (-7460 3460);
PAINT MONO (-7460 3460);
FORCEPROP 0 LASTPIN (-7450 3950) $PN 60
J 2
(-7460 3960);
DISPLAY 0.680851 (-7460 3960);
PAINT MONO (-7460 3960);
FORCEPROP 0 LASTPIN (-7450 3500) $PN 91
J 2
(-7460 3510);
DISPLAY 0.680851 (-7460 3510);
PAINT MONO (-7460 3510);
FORCEPROP 0 LASTPIN (-7450 4000) $PN 203
J 2
(-7460 4010);
DISPLAY 0.680851 (-7460 4010);
PAINT MONO (-7460 4010);
FORCEPROP 0 LASTPIN (-7450 3550) $PN 234
J 2
(-7460 3560);
DISPLAY 0.680851 (-7460 3560);
PAINT MONO (-7460 3560);
FORCEPROP 0 LASTPIN (-7450 4050) $PN 205
J 2
(-7460 4060);
DISPLAY 0.680851 (-7460 4060);
PAINT MONO (-7460 4060);
FORCEPROP 0 LASTPIN (-7450 3600) $PN 236
J 2
(-7460 3610);
DISPLAY 0.680851 (-7460 3610);
PAINT MONO (-7460 3610);
FORCEPROP 0 LASTPIN (-7450 4150) $PN 218
J 2
(-7460 4160);
DISPLAY 0.680851 (-7460 4160);
PAINT MONO (-7460 4160);
FORCEPROP 0 LASTPIN (-7450 4200) $PN 217
J 2
(-7460 4210);
DISPLAY 0.680851 (-7460 4210);
PAINT MONO (-7460 4210);
FORCEPROP 0 LASTPIN (-7450 4450) $PN 64
J 2
(-7460 4460);
DISPLAY 0.680851 (-7460 4460);
PAINT MONO (-7460 4460);
FORCEPROP 0 LASTPIN (-7450 4300) $PN 84
J 2
(-7460 4310);
DISPLAY 0.680851 (-7460 4310);
PAINT MONO (-7460 4310);
FORCEPROP 0 LASTPIN (-7450 4500) $PN 209
J 2
(-7460 4510);
DISPLAY 0.680851 (-7460 4510);
PAINT MONO (-7460 4510);
FORCEPROP 0 LASTPIN (-7450 4350) $PN 229
J 2
(-7460 4360);
DISPLAY 0.680851 (-7460 4360);
PAINT MONO (-7460 4360);
FORCEPROP 0 LASTPIN (-6250 3900) $PN 7
J 0
(-6240 3910);
DISPLAY 0.680851 (-6240 3910);
PAINT MONO (-6240 3910);
FORCEPROP 0 LASTPIN (-6250 2250) $PN 100
J 0
(-6240 2260);
DISPLAY 0.680851 (-6240 2260);
PAINT MONO (-6240 2260);
FORCEPROP 0 LASTPIN (-6250 3950) $PN 9
J 0
(-6240 3960);
DISPLAY 0.680851 (-6240 3960);
PAINT MONO (-6240 3960);
FORCEPROP 0 LASTPIN (-6250 2300) $PN 102
J 0
(-6240 2310);
DISPLAY 0.680851 (-6240 2310);
PAINT MONO (-6240 2310);
FORCEPROP 0 LASTPIN (-6250 4000) $PN 152
J 0
(-6240 4010);
DISPLAY 0.680851 (-6240 4010);
PAINT MONO (-6240 4010);
FORCEPROP 0 LASTPIN (-6250 2350) $PN 245
J 0
(-6240 2360);
DISPLAY 0.680851 (-6240 2360);
PAINT MONO (-6240 2360);
FORCEPROP 0 LASTPIN (-6250 4050) $PN 154
J 0
(-6240 4060);
DISPLAY 0.680851 (-6240 4060);
PAINT MONO (-6240 4060);
FORCEPROP 0 LASTPIN (-6250 2400) $PN 247
J 0
(-6240 2410);
DISPLAY 0.680851 (-6240 2410);
PAINT MONO (-6240 2410);
FORCEPROP 0 LASTPIN (-6250 4100) $PN 14
J 0
(-6240 4110);
DISPLAY 0.680851 (-6240 4110);
PAINT MONO (-6240 4110);
FORCEPROP 0 LASTPIN (-6250 2450) $PN 107
J 0
(-6240 2460);
DISPLAY 0.680851 (-6240 2460);
PAINT MONO (-6240 2460);
FORCEPROP 0 LASTPIN (-6250 4150) $PN 16
J 0
(-6240 4160);
DISPLAY 0.680851 (-6240 4160);
PAINT MONO (-6240 4160);
FORCEPROP 0 LASTPIN (-6250 2500) $PN 109
J 0
(-6240 2510);
DISPLAY 0.680851 (-6240 2510);
PAINT MONO (-6240 2510);
FORCEPROP 0 LASTPIN (-6250 4200) $PN 159
J 0
(-6240 4210);
DISPLAY 0.680851 (-6240 4210);
PAINT MONO (-6240 4210);
FORCEPROP 0 LASTPIN (-6250 2550) $PN 252
J 0
(-6240 2560);
DISPLAY 0.680851 (-6240 2560);
PAINT MONO (-6240 2560);
FORCEPROP 0 LASTPIN (-6250 4250) $PN 161
J 0
(-6240 4260);
DISPLAY 0.680851 (-6240 4260);
PAINT MONO (-6240 4260);
FORCEPROP 0 LASTPIN (-6250 2600) $PN 254
J 0
(-6240 2610);
DISPLAY 0.680851 (-6240 2610);
PAINT MONO (-6240 2610);
FORCEPROP 0 LASTPIN (-6250 4300) $PN 18
J 0
(-6240 4310);
DISPLAY 0.680851 (-6240 4310);
PAINT MONO (-6240 4310);
FORCEPROP 0 LASTPIN (-6250 2650) $PN 111
J 0
(-6240 2660);
DISPLAY 0.680851 (-6240 2660);
PAINT MONO (-6240 2660);
FORCEPROP 0 LASTPIN (-6250 4350) $PN 20
J 0
(-6240 4360);
DISPLAY 0.680851 (-6240 4360);
PAINT MONO (-6240 4360);
FORCEPROP 0 LASTPIN (-6250 2700) $PN 113
J 0
(-6240 2710);
DISPLAY 0.680851 (-6240 2710);
PAINT MONO (-6240 2710);
FORCEPROP 0 LASTPIN (-6250 4400) $PN 163
J 0
(-6240 4410);
DISPLAY 0.680851 (-6240 4410);
PAINT MONO (-6240 4410);
FORCEPROP 0 LASTPIN (-6250 2750) $PN 256
J 0
(-6240 2760);
DISPLAY 0.680851 (-6240 2760);
PAINT MONO (-6240 2760);
FORCEPROP 0 LASTPIN (-6250 4450) $PN 165
J 0
(-6240 4460);
DISPLAY 0.680851 (-6240 4460);
PAINT MONO (-6240 4460);
FORCEPROP 0 LASTPIN (-6250 2800) $PN 258
J 0
(-6240 2810);
DISPLAY 0.680851 (-6240 2810);
PAINT MONO (-6240 2810);
FORCEPROP 0 LASTPIN (-6250 4500) $PN 25
J 0
(-6240 4510);
DISPLAY 0.680851 (-6240 4510);
PAINT MONO (-6240 4510);
FORCEPROP 0 LASTPIN (-6250 2850) $PN 118
J 0
(-6240 2860);
DISPLAY 0.680851 (-6240 2860);
PAINT MONO (-6240 2860);
FORCEPROP 0 LASTPIN (-6250 4550) $PN 27
J 0
(-6240 4560);
DISPLAY 0.680851 (-6240 4560);
PAINT MONO (-6240 4560);
FORCEPROP 0 LASTPIN (-6250 2900) $PN 120
J 0
(-6240 2910);
DISPLAY 0.680851 (-6240 2910);
PAINT MONO (-6240 2910);
FORCEPROP 0 LASTPIN (-6250 4600) $PN 170
J 0
(-6240 4610);
DISPLAY 0.680851 (-6240 4610);
PAINT MONO (-6240 4610);
FORCEPROP 0 LASTPIN (-6250 2950) $PN 263
J 0
(-6240 2960);
DISPLAY 0.680851 (-6240 2960);
PAINT MONO (-6240 2960);
FORCEPROP 0 LASTPIN (-6250 4650) $PN 172
J 0
(-6240 4660);
DISPLAY 0.680851 (-6240 4660);
PAINT MONO (-6240 4660);
FORCEPROP 0 LASTPIN (-6250 3000) $PN 265
J 0
(-6240 3010);
DISPLAY 0.680851 (-6240 3010);
PAINT MONO (-6240 3010);
FORCEPROP 0 LASTPIN (-6250 4700) $PN 29
J 0
(-6240 4710);
DISPLAY 0.680851 (-6240 4710);
PAINT MONO (-6240 4710);
FORCEPROP 0 LASTPIN (-6250 3050) $PN 122
J 0
(-6240 3060);
DISPLAY 0.680851 (-6240 3060);
PAINT MONO (-6240 3060);
FORCEPROP 0 LASTPIN (-6250 4750) $PN 31
J 0
(-6240 4760);
DISPLAY 0.680851 (-6240 4760);
PAINT MONO (-6240 4760);
FORCEPROP 0 LASTPIN (-6250 3100) $PN 124
J 0
(-6240 3110);
DISPLAY 0.680851 (-6240 3110);
PAINT MONO (-6240 3110);
FORCEPROP 0 LASTPIN (-6250 4800) $PN 174
J 0
(-6240 4810);
DISPLAY 0.680851 (-6240 4810);
PAINT MONO (-6240 4810);
FORCEPROP 0 LASTPIN (-6250 3150) $PN 267
J 0
(-6240 3160);
DISPLAY 0.680851 (-6240 3160);
PAINT MONO (-6240 3160);
FORCEPROP 0 LASTPIN (-6250 4850) $PN 176
J 0
(-6240 4860);
DISPLAY 0.680851 (-6240 4860);
PAINT MONO (-6240 4860);
FORCEPROP 0 LASTPIN (-6250 3200) $PN 269
J 0
(-6240 3210);
DISPLAY 0.680851 (-6240 3210);
PAINT MONO (-6240 3210);
FORCEPROP 0 LASTPIN (-6250 4900) $PN 36
J 0
(-6240 4910);
DISPLAY 0.680851 (-6240 4910);
PAINT MONO (-6240 4910);
FORCEPROP 0 LASTPIN (-6250 3250) $PN 129
J 0
(-6240 3260);
DISPLAY 0.680851 (-6240 3260);
PAINT MONO (-6240 3260);
FORCEPROP 0 LASTPIN (-6250 4950) $PN 38
J 0
(-6240 4960);
DISPLAY 0.680851 (-6240 4960);
PAINT MONO (-6240 4960);
FORCEPROP 0 LASTPIN (-6250 3300) $PN 131
J 0
(-6240 3310);
DISPLAY 0.680851 (-6240 3310);
PAINT MONO (-6240 3310);
FORCEPROP 0 LASTPIN (-6250 5000) $PN 181
J 0
(-6240 5010);
DISPLAY 0.680851 (-6240 5010);
PAINT MONO (-6240 5010);
FORCEPROP 0 LASTPIN (-6250 3350) $PN 274
J 0
(-6240 3360);
DISPLAY 0.680851 (-6240 3360);
PAINT MONO (-6240 3360);
FORCEPROP 0 LASTPIN (-6250 5050) $PN 183
J 0
(-6240 5060);
DISPLAY 0.680851 (-6240 5060);
PAINT MONO (-6240 5060);
FORCEPROP 0 LASTPIN (-6250 3400) $PN 276
J 0
(-6240 3410);
DISPLAY 0.680851 (-6240 3410);
PAINT MONO (-6240 3410);
FORCEPROP 0 LASTPIN (-6250 5100) $PN 40
J 0
(-6240 5110);
DISPLAY 0.680851 (-6240 5110);
PAINT MONO (-6240 5110);
FORCEPROP 0 LASTPIN (-6250 3450) $PN 133
J 0
(-6240 3460);
DISPLAY 0.680851 (-6240 3460);
PAINT MONO (-6240 3460);
FORCEPROP 0 LASTPIN (-6250 5150) $PN 42
J 0
(-6240 5160);
DISPLAY 0.680851 (-6240 5160);
PAINT MONO (-6240 5160);
FORCEPROP 0 LASTPIN (-6250 3500) $PN 135
J 0
(-6240 3510);
DISPLAY 0.680851 (-6240 3510);
PAINT MONO (-6240 3510);
FORCEPROP 0 LASTPIN (-6250 5200) $PN 185
J 0
(-6240 5210);
DISPLAY 0.680851 (-6240 5210);
PAINT MONO (-6240 5210);
FORCEPROP 0 LASTPIN (-6250 3550) $PN 278
J 0
(-6240 3560);
DISPLAY 0.680851 (-6240 3560);
PAINT MONO (-6240 3560);
FORCEPROP 0 LASTPIN (-6250 5250) $PN 187
J 0
(-6240 5260);
DISPLAY 0.680851 (-6240 5260);
PAINT MONO (-6240 5260);
FORCEPROP 0 LASTPIN (-6250 3600) $PN 280
J 0
(-6240 3610);
DISPLAY 0.680851 (-6240 3610);
PAINT MONO (-6240 3610);
FORCEPROP 0 LASTPIN (-6250 5300) $PN 47
J 0
(-6240 5310);
DISPLAY 0.680851 (-6240 5310);
PAINT MONO (-6240 5310);
FORCEPROP 0 LASTPIN (-6250 3650) $PN 140
J 0
(-6240 3660);
DISPLAY 0.680851 (-6240 3660);
PAINT MONO (-6240 3660);
FORCEPROP 0 LASTPIN (-6250 5350) $PN 49
J 0
(-6240 5360);
DISPLAY 0.680851 (-6240 5360);
PAINT MONO (-6240 5360);
FORCEPROP 0 LASTPIN (-6250 3700) $PN 142
J 0
(-6240 3710);
DISPLAY 0.680851 (-6240 3710);
PAINT MONO (-6240 3710);
FORCEPROP 0 LASTPIN (-6250 5400) $PN 192
J 0
(-6240 5410);
DISPLAY 0.680851 (-6240 5410);
PAINT MONO (-6240 5410);
FORCEPROP 0 LASTPIN (-6250 3750) $PN 285
J 0
(-6240 3760);
DISPLAY 0.680851 (-6240 3760);
PAINT MONO (-6240 3760);
FORCEPROP 0 LASTPIN (-6250 5450) $PN 194
J 0
(-6240 5460);
DISPLAY 0.680851 (-6240 5460);
PAINT MONO (-6240 5460);
FORCEPROP 0 LASTPIN (-6250 3800) $PN 287
J 0
(-6240 3810);
DISPLAY 0.680851 (-6240 3810);
PAINT MONO (-6240 3810);
FORCEPROP 0 LASTPIN (-7450 2950) $PN 148
J 2
(-7460 2960);
DISPLAY 0.680851 (-7460 2960);
PAINT MONO (-7460 2960);
FORCEPROP 0 LASTPIN (-7450 2850) $PN 4
J 2
(-7460 2860);
DISPLAY 0.680851 (-7460 2860);
PAINT MONO (-7460 2860);
FORCEPROP 0 LASTPIN (-7450 2900) $PN 5
J 2
(-7460 2910);
DISPLAY 0.680851 (-7460 2910);
PAINT MONO (-7460 2910);
FORCEPROP 0 LASTPIN (-7450 2050) $PN 86
J 2
(-7460 2060);
DISPLAY 0.680851 (-7460 2060);
PAINT MONO (-7460 2060);
FORCEPROP 0 LASTPIN (-7450 2000) $PN 87
J 2
(-7460 2010);
DISPLAY 0.680851 (-7460 2010);
PAINT MONO (-7460 2010);
FORCEPROP 0 LASTPIN (-7450 4650) $PN 74
J 2
(-7460 4660);
DISPLAY 0.680851 (-7460 4660);
PAINT MONO (-7460 4660);
FORCEPROP 0 LASTPIN (-7450 4600) $PN 227
J 2
(-7460 4610);
DISPLAY 0.680851 (-7460 4610);
PAINT MONO (-7460 4610);
FORCEPROP 0 LASTPIN (-7450 2600) $PN 147
J 2
(-7460 2610);
DISPLAY 0.680851 (-7460 2610);
PAINT MONO (-7460 2610);
FORCEPROP 0 LASTPIN (-7450 3150) $PN 207
J 2
(-7460 3160);
DISPLAY 0.680851 (-7460 3160);
PAINT MONO (-7460 3160);
FORCEPROP 0 LASTPIN (-7450 2200) $PN 2
J 2
(-7460 2210);
DISPLAY 0.680851 (-7460 2210);
PAINT MONO (-7460 2210);
FORCEPROP 0 LASTPIN (-7450 2250) $PN 144
J 2
(-7460 2260);
DISPLAY 0.680851 (-7460 2260);
PAINT MONO (-7460 2260);
FORCEPROP 0 LASTPIN (-7450 2300) $PN 149
J 2
(-7460 2310);
DISPLAY 0.680851 (-7460 2310);
PAINT MONO (-7460 2310);
FORCEPROP 0 LASTPIN (-7450 2350) $PN 150
J 2
(-7460 2360);
DISPLAY 0.680851 (-7460 2360);
PAINT MONO (-7460 2360);
FORCEPROP 0 LASTPIN (-7450 2400) $PN 220
J 2
(-7460 2410);
DISPLAY 0.680851 (-7460 2410);
PAINT MONO (-7460 2410);
FORCEPROP 0 LASTPIN (-7450 2450) $PN 231
J 2
(-7460 2460);
DISPLAY 0.680851 (-7460 2460);
PAINT MONO (-7460 2460);
FORCEPROP 0 LASTPIN (-7450 2500) $PN 232
J 2
(-7460 2510);
DISPLAY 0.680851 (-7460 2510);
PAINT MONO (-7460 2510);
FORCEPROP 0 LASTPIN (-7450 3000) $PN 3
J 2
(-7460 3010);
DISPLAY 0.680851 (-7460 3010);
PAINT MONO (-7460 3010);
FORCEPROP 1 LAST PART_NUMBER DFHST8FS479
J 0
(-7300 5700);
DISPLAY 0.468085 (-7300 5700);
PAINT SKYBLUE (-7300 5700);
FORCEPROP 1 LAST MATERIAL IO
J 0
(-7300 5625);
DISPLAY 0.468085 (-7300 5625);
PAINT SKYBLUE (-7300 5625);
FORCEPROP 2 LAST VALUE SCONN288_DDR506112002KQ
J 0
(-7300 5825);
DISPLAY 0.489362 (-7300 5825);
PAINT SKYBLUE (-7300 5825);
FORCEPROP 2 LAST PART_TYPE SMLF
J 0
(-7300 5875);
DISPLAY 1.021277 (-7300 5875);
FORCEPROP 1 LAST CDS_LMAN_SYM_OUTLINE -450,1900,450,-1850
J 0
(-6850 3700);
DISPLAY 0.468085 (-6850 3700);
PAINT GREEN (-6850 3700);
DISPLAY INVISIBLE (-6850 3700);
FORCEPROP 1 LAST PATH I22
J 0
(-6850 3700);
DISPLAY 0.723404 (-6850 3700);
PAINT GREEN (-6850 3700);
DISPLAY INVISIBLE (-6850 3700);
FORCEPROP 1 LAST NEEDS_NO_SIZE TRUE
J 0
(-6850 3700);
DISPLAY 0.723404 (-6850 3700);
PAINT GREEN (-6850 3700);
DISPLAY INVISIBLE (-6850 3700);
FORCEPROP 2 LAST CDS_LIB pure_quanta
J 0
(-6850 3700);
DISPLAY INVISIBLE (-6850 3700);
FORCEADD TAP..1
(-3250 3200);
FORCEPROP 3 LASTPIN (-3300 3200) SIG_NAME M_I_CPU0_SB_DQS_DN<7>
J 0
(-3290 3210);
DISPLAY 0.659574 (-3290 3210);
PAINT MONO (-3290 3210);
DISPLAY INVISIBLE (-3290 3210);
FORCEPROP 1 LASTPIN (-3300 3200) BN 7
J 0
(-3312 3208);
DISPLAY 0.489362 (-3312 3208);
PAINT GREEN (-3312 3208);
FORCEPROP 2 LAST CDS_LIB mstr_standard
J 0
(-3250 3200);
DISPLAY 0.723404 (-3250 3200);
PAINT MONO (-3250 3200);
DISPLAY INVISIBLE (-3250 3200);
FORCEPROP 1 LAST BODY_TYPE PLUMBING
J 0
(-3250 3250);
DISPLAY 0.872340 (-3250 3250);
PAINT GREEN (-3250 3250);
DISPLAY INVISIBLE (-3250 3250);
FORCEPROP 1 LAST HDL_TAP TRUE
J 0
(-2925 3075);
DISPLAY 0.872340 (-2925 3075);
DISPLAY INVISIBLE (-2925 3075);
FORCEPROP 1 LAST PATH I220
J 0
(-3252 3200);
DISPLAY 0.872340 (-3252 3200);
PAINT GREEN (-3252 3200);
DISPLAY INVISIBLE (-3252 3200);
FORCEADD TAP..1
(-3250 3100);
FORCEPROP 3 LASTPIN (-3300 3100) SIG_NAME M_I_CPU0_SB_DQS_DN<6>
J 0
(-3290 3110);
DISPLAY 0.659574 (-3290 3110);
PAINT MONO (-3290 3110);
DISPLAY INVISIBLE (-3290 3110);
FORCEPROP 1 LASTPIN (-3300 3100) BN 6
J 0
(-3312 3108);
DISPLAY 0.489362 (-3312 3108);
PAINT GREEN (-3312 3108);
FORCEPROP 2 LAST CDS_LIB mstr_standard
J 0
(-3250 3100);
DISPLAY 0.723404 (-3250 3100);
PAINT MONO (-3250 3100);
DISPLAY INVISIBLE (-3250 3100);
FORCEPROP 1 LAST BODY_TYPE PLUMBING
J 0
(-3250 3150);
DISPLAY 0.872340 (-3250 3150);
PAINT GREEN (-3250 3150);
DISPLAY INVISIBLE (-3250 3150);
FORCEPROP 1 LAST HDL_TAP TRUE
J 0
(-2925 2975);
DISPLAY 0.872340 (-2925 2975);
DISPLAY INVISIBLE (-2925 2975);
FORCEPROP 1 LAST PATH I221
J 0
(-3252 3100);
DISPLAY 0.872340 (-3252 3100);
PAINT GREEN (-3252 3100);
DISPLAY INVISIBLE (-3252 3100);
FORCEADD TAP..1
(-3250 3000);
FORCEPROP 3 LASTPIN (-3300 3000) SIG_NAME M_I_CPU0_SB_DQS_DN<5>
J 0
(-3290 3010);
DISPLAY 0.659574 (-3290 3010);
PAINT MONO (-3290 3010);
DISPLAY INVISIBLE (-3290 3010);
FORCEPROP 1 LASTPIN (-3300 3000) BN 5
J 0
(-3312 3008);
DISPLAY 0.489362 (-3312 3008);
PAINT GREEN (-3312 3008);
FORCEPROP 2 LAST CDS_LIB mstr_standard
J 0
(-3250 3000);
DISPLAY 0.723404 (-3250 3000);
PAINT MONO (-3250 3000);
DISPLAY INVISIBLE (-3250 3000);
FORCEPROP 1 LAST BODY_TYPE PLUMBING
J 0
(-3250 3050);
DISPLAY 0.872340 (-3250 3050);
PAINT GREEN (-3250 3050);
DISPLAY INVISIBLE (-3250 3050);
FORCEPROP 1 LAST HDL_TAP TRUE
J 0
(-2925 2875);
DISPLAY 0.872340 (-2925 2875);
DISPLAY INVISIBLE (-2925 2875);
FORCEPROP 1 LAST PATH I222
J 0
(-3252 3000);
DISPLAY 0.872340 (-3252 3000);
PAINT GREEN (-3252 3000);
DISPLAY INVISIBLE (-3252 3000);
FORCEADD TAP..1
(-3250 2900);
FORCEPROP 3 LASTPIN (-3300 2900) SIG_NAME M_I_CPU0_SB_DQS_DN<4>
J 0
(-3290 2910);
DISPLAY 0.659574 (-3290 2910);
PAINT MONO (-3290 2910);
DISPLAY INVISIBLE (-3290 2910);
FORCEPROP 1 LASTPIN (-3300 2900) BN 4
J 0
(-3312 2908);
DISPLAY 0.489362 (-3312 2908);
PAINT GREEN (-3312 2908);
FORCEPROP 2 LAST CDS_LIB mstr_standard
J 0
(-3250 2900);
DISPLAY 0.723404 (-3250 2900);
PAINT MONO (-3250 2900);
DISPLAY INVISIBLE (-3250 2900);
FORCEPROP 1 LAST BODY_TYPE PLUMBING
J 0
(-3250 2950);
DISPLAY 0.872340 (-3250 2950);
PAINT GREEN (-3250 2950);
DISPLAY INVISIBLE (-3250 2950);
FORCEPROP 1 LAST HDL_TAP TRUE
J 0
(-2925 2775);
DISPLAY 0.872340 (-2925 2775);
DISPLAY INVISIBLE (-2925 2775);
FORCEPROP 1 LAST PATH I223
J 0
(-3252 2900);
DISPLAY 0.872340 (-3252 2900);
PAINT GREEN (-3252 2900);
DISPLAY INVISIBLE (-3252 2900);
FORCEADD TAP..1
(-3250 2800);
FORCEPROP 3 LASTPIN (-3300 2800) SIG_NAME M_I_CPU0_SB_DQS_DN<3>
J 0
(-3290 2810);
DISPLAY 0.659574 (-3290 2810);
PAINT MONO (-3290 2810);
DISPLAY INVISIBLE (-3290 2810);
FORCEPROP 1 LASTPIN (-3300 2800) BN 3
J 0
(-3312 2808);
DISPLAY 0.489362 (-3312 2808);
PAINT GREEN (-3312 2808);
FORCEPROP 2 LAST CDS_LIB mstr_standard
J 0
(-3250 2800);
DISPLAY 0.723404 (-3250 2800);
PAINT MONO (-3250 2800);
DISPLAY INVISIBLE (-3250 2800);
FORCEPROP 1 LAST BODY_TYPE PLUMBING
J 0
(-3250 2850);
DISPLAY 0.872340 (-3250 2850);
PAINT GREEN (-3250 2850);
DISPLAY INVISIBLE (-3250 2850);
FORCEPROP 1 LAST HDL_TAP TRUE
J 0
(-2925 2675);
DISPLAY 0.872340 (-2925 2675);
DISPLAY INVISIBLE (-2925 2675);
FORCEPROP 1 LAST PATH I224
J 0
(-3252 2800);
DISPLAY 0.872340 (-3252 2800);
PAINT GREEN (-3252 2800);
DISPLAY INVISIBLE (-3252 2800);
FORCEADD TAP..1
(-3250 2700);
FORCEPROP 3 LASTPIN (-3300 2700) SIG_NAME M_I_CPU0_SB_DQS_DN<2>
J 0
(-3290 2710);
DISPLAY 0.659574 (-3290 2710);
PAINT MONO (-3290 2710);
DISPLAY INVISIBLE (-3290 2710);
FORCEPROP 1 LASTPIN (-3300 2700) BN 2
J 0
(-3312 2708);
DISPLAY 0.489362 (-3312 2708);
PAINT GREEN (-3312 2708);
FORCEPROP 2 LAST CDS_LIB mstr_standard
J 0
(-3250 2700);
DISPLAY 0.723404 (-3250 2700);
PAINT MONO (-3250 2700);
DISPLAY INVISIBLE (-3250 2700);
FORCEPROP 1 LAST BODY_TYPE PLUMBING
J 0
(-3250 2750);
DISPLAY 0.872340 (-3250 2750);
PAINT GREEN (-3250 2750);
DISPLAY INVISIBLE (-3250 2750);
FORCEPROP 1 LAST HDL_TAP TRUE
J 0
(-2925 2575);
DISPLAY 0.872340 (-2925 2575);
DISPLAY INVISIBLE (-2925 2575);
FORCEPROP 1 LAST PATH I225
J 0
(-3252 2700);
DISPLAY 0.872340 (-3252 2700);
PAINT GREEN (-3252 2700);
DISPLAY INVISIBLE (-3252 2700);
FORCEADD TAP..1
(-3250 2600);
FORCEPROP 3 LASTPIN (-3300 2600) SIG_NAME M_I_CPU0_SB_DQS_DN<1>
J 0
(-3290 2610);
DISPLAY 0.659574 (-3290 2610);
PAINT MONO (-3290 2610);
DISPLAY INVISIBLE (-3290 2610);
FORCEPROP 1 LASTPIN (-3300 2600) BN 1
J 0
(-3312 2608);
DISPLAY 0.489362 (-3312 2608);
PAINT GREEN (-3312 2608);
FORCEPROP 2 LAST CDS_LIB mstr_standard
J 0
(-3250 2600);
DISPLAY 0.723404 (-3250 2600);
PAINT MONO (-3250 2600);
DISPLAY INVISIBLE (-3250 2600);
FORCEPROP 1 LAST BODY_TYPE PLUMBING
J 0
(-3250 2650);
DISPLAY 0.872340 (-3250 2650);
PAINT GREEN (-3250 2650);
DISPLAY INVISIBLE (-3250 2650);
FORCEPROP 1 LAST HDL_TAP TRUE
J 0
(-2925 2475);
DISPLAY 0.872340 (-2925 2475);
DISPLAY INVISIBLE (-2925 2475);
FORCEPROP 1 LAST PATH I226
J 0
(-3252 2600);
DISPLAY 0.872340 (-3252 2600);
PAINT GREEN (-3252 2600);
DISPLAY INVISIBLE (-3252 2600);
FORCEADD TAP..1
(-3250 2500);
FORCEPROP 3 LASTPIN (-3300 2500) SIG_NAME M_I_CPU0_SB_DQS_DN<0>
J 0
(-3290 2510);
DISPLAY 0.659574 (-3290 2510);
PAINT MONO (-3290 2510);
DISPLAY INVISIBLE (-3290 2510);
FORCEPROP 1 LASTPIN (-3300 2500) BN 0
J 0
(-3312 2508);
DISPLAY 0.489362 (-3312 2508);
PAINT GREEN (-3312 2508);
FORCEPROP 2 LAST CDS_LIB mstr_standard
J 0
(-3250 2500);
DISPLAY 0.723404 (-3250 2500);
PAINT MONO (-3250 2500);
DISPLAY INVISIBLE (-3250 2500);
FORCEPROP 1 LAST BODY_TYPE PLUMBING
J 0
(-3250 2550);
DISPLAY 0.872340 (-3250 2550);
PAINT GREEN (-3250 2550);
DISPLAY INVISIBLE (-3250 2550);
FORCEPROP 1 LAST HDL_TAP TRUE
J 0
(-2925 2375);
DISPLAY 0.872340 (-2925 2375);
DISPLAY INVISIBLE (-2925 2375);
FORCEPROP 1 LAST PATH I227
J 0
(-3252 2500);
DISPLAY 0.872340 (-3252 2500);
PAINT GREEN (-3252 2500);
DISPLAY INVISIBLE (-3252 2500);
FORCEADD TAP..1
(-3450 3150);
FORCEPROP 3 LASTPIN (-3500 3150) SIG_NAME M_I_CPU0_SB_DQS_DP<6>
J 0
(-3490 3160);
DISPLAY 0.659574 (-3490 3160);
PAINT MONO (-3490 3160);
DISPLAY INVISIBLE (-3490 3160);
FORCEPROP 1 LASTPIN (-3500 3150) BN 6
J 0
(-3512 3158);
DISPLAY 0.489362 (-3512 3158);
PAINT GREEN (-3512 3158);
FORCEPROP 2 LAST CDS_LIB mstr_standard
J 0
(-3450 3150);
DISPLAY 0.723404 (-3450 3150);
PAINT MONO (-3450 3150);
DISPLAY INVISIBLE (-3450 3150);
FORCEPROP 1 LAST BODY_TYPE PLUMBING
J 0
(-3450 3200);
DISPLAY 0.872340 (-3450 3200);
PAINT GREEN (-3450 3200);
DISPLAY INVISIBLE (-3450 3200);
FORCEPROP 1 LAST HDL_TAP TRUE
J 0
(-3125 3025);
DISPLAY 0.872340 (-3125 3025);
DISPLAY INVISIBLE (-3125 3025);
FORCEPROP 1 LAST PATH I228
J 0
(-3452 3150);
DISPLAY 0.872340 (-3452 3150);
PAINT GREEN (-3452 3150);
DISPLAY INVISIBLE (-3452 3150);
FORCEADD TAP..1
(-3450 3250);
FORCEPROP 3 LASTPIN (-3500 3250) SIG_NAME M_I_CPU0_SB_DQS_DP<7>
J 0
(-3490 3260);
DISPLAY 0.659574 (-3490 3260);
PAINT MONO (-3490 3260);
DISPLAY INVISIBLE (-3490 3260);
FORCEPROP 1 LASTPIN (-3500 3250) BN 7
J 0
(-3512 3258);
DISPLAY 0.489362 (-3512 3258);
PAINT GREEN (-3512 3258);
FORCEPROP 2 LAST CDS_LIB mstr_standard
J 0
(-3450 3250);
DISPLAY 0.723404 (-3450 3250);
PAINT MONO (-3450 3250);
DISPLAY INVISIBLE (-3450 3250);
FORCEPROP 1 LAST BODY_TYPE PLUMBING
J 0
(-3450 3300);
DISPLAY 0.872340 (-3450 3300);
PAINT GREEN (-3450 3300);
DISPLAY INVISIBLE (-3450 3300);
FORCEPROP 1 LAST HDL_TAP TRUE
J 0
(-3125 3125);
DISPLAY 0.872340 (-3125 3125);
DISPLAY INVISIBLE (-3125 3125);
FORCEPROP 1 LAST PATH I229
J 0
(-3452 3250);
DISPLAY 0.872340 (-3452 3250);
PAINT GREEN (-3452 3250);
DISPLAY INVISIBLE (-3452 3250);
FORCEADD TAP..1
R 2
(-7700 3350);
FORCEPROP 3 LASTPIN (-7650 3350) SIG_NAME M_I_CPU0_SB_CB<2>
J 0
(-7640 3360);
DISPLAY 0.659574 (-7640 3360);
PAINT MONO (-7640 3360);
DISPLAY INVISIBLE (-7640 3360);
FORCEPROP 1 LASTPIN (-7650 3350) BN 2
J 2
(-7638 3358);
DISPLAY 0.489362 (-7638 3358);
PAINT GREEN (-7638 3358);
FORCEPROP 2 LAST CDS_LIB mstr_standard
J 0
(-7700 3350);
DISPLAY 0.723404 (-7700 3350);
PAINT MONO (-7700 3350);
DISPLAY INVISIBLE (-7700 3350);
FORCEPROP 1 LAST BODY_TYPE PLUMBING
J 2
(-7700 3400);
DISPLAY 0.872340 (-7700 3400);
PAINT GREEN (-7700 3400);
DISPLAY INVISIBLE (-7700 3400);
FORCEPROP 1 LAST HDL_TAP TRUE
J 2
(-8025 3225);
DISPLAY 0.872340 (-8025 3225);
DISPLAY INVISIBLE (-8025 3225);
FORCEPROP 1 LAST PATH I23
J 2
(-7698 3350);
DISPLAY 0.872340 (-7698 3350);
PAINT GREEN (-7698 3350);
DISPLAY INVISIBLE (-7698 3350);
FORCEADD TAP..1
(-3450 3050);
FORCEPROP 3 LASTPIN (-3500 3050) SIG_NAME M_I_CPU0_SB_DQS_DP<5>
J 0
(-3490 3060);
DISPLAY 0.659574 (-3490 3060);
PAINT MONO (-3490 3060);
DISPLAY INVISIBLE (-3490 3060);
FORCEPROP 1 LASTPIN (-3500 3050) BN 5
J 0
(-3512 3058);
DISPLAY 0.489362 (-3512 3058);
PAINT GREEN (-3512 3058);
FORCEPROP 2 LAST CDS_LIB mstr_standard
J 0
(-3450 3050);
DISPLAY 0.723404 (-3450 3050);
PAINT MONO (-3450 3050);
DISPLAY INVISIBLE (-3450 3050);
FORCEPROP 1 LAST BODY_TYPE PLUMBING
J 0
(-3450 3100);
DISPLAY 0.872340 (-3450 3100);
PAINT GREEN (-3450 3100);
DISPLAY INVISIBLE (-3450 3100);
FORCEPROP 1 LAST HDL_TAP TRUE
J 0
(-3125 2925);
DISPLAY 0.872340 (-3125 2925);
DISPLAY INVISIBLE (-3125 2925);
FORCEPROP 1 LAST PATH I230
J 0
(-3452 3050);
DISPLAY 0.872340 (-3452 3050);
PAINT GREEN (-3452 3050);
DISPLAY INVISIBLE (-3452 3050);
FORCEADD TAP..1
(-3450 2950);
FORCEPROP 3 LASTPIN (-3500 2950) SIG_NAME M_I_CPU0_SB_DQS_DP<4>
J 0
(-3490 2960);
DISPLAY 0.659574 (-3490 2960);
PAINT MONO (-3490 2960);
DISPLAY INVISIBLE (-3490 2960);
FORCEPROP 1 LASTPIN (-3500 2950) BN 4
J 0
(-3512 2958);
DISPLAY 0.489362 (-3512 2958);
PAINT GREEN (-3512 2958);
FORCEPROP 2 LAST CDS_LIB mstr_standard
J 0
(-3450 2950);
DISPLAY 0.723404 (-3450 2950);
PAINT MONO (-3450 2950);
DISPLAY INVISIBLE (-3450 2950);
FORCEPROP 1 LAST BODY_TYPE PLUMBING
J 0
(-3450 3000);
DISPLAY 0.872340 (-3450 3000);
PAINT GREEN (-3450 3000);
DISPLAY INVISIBLE (-3450 3000);
FORCEPROP 1 LAST HDL_TAP TRUE
J 0
(-3125 2825);
DISPLAY 0.872340 (-3125 2825);
DISPLAY INVISIBLE (-3125 2825);
FORCEPROP 1 LAST PATH I231
J 0
(-3452 2950);
DISPLAY 0.872340 (-3452 2950);
PAINT GREEN (-3452 2950);
DISPLAY INVISIBLE (-3452 2950);
FORCEADD TAP..1
(-3450 2850);
FORCEPROP 3 LASTPIN (-3500 2850) SIG_NAME M_I_CPU0_SB_DQS_DP<3>
J 0
(-3490 2860);
DISPLAY 0.659574 (-3490 2860);
PAINT MONO (-3490 2860);
DISPLAY INVISIBLE (-3490 2860);
FORCEPROP 1 LASTPIN (-3500 2850) BN 3
J 0
(-3512 2858);
DISPLAY 0.489362 (-3512 2858);
PAINT GREEN (-3512 2858);
FORCEPROP 2 LAST CDS_LIB mstr_standard
J 0
(-3450 2850);
DISPLAY 0.723404 (-3450 2850);
PAINT MONO (-3450 2850);
DISPLAY INVISIBLE (-3450 2850);
FORCEPROP 1 LAST BODY_TYPE PLUMBING
J 0
(-3450 2900);
DISPLAY 0.872340 (-3450 2900);
PAINT GREEN (-3450 2900);
DISPLAY INVISIBLE (-3450 2900);
FORCEPROP 1 LAST HDL_TAP TRUE
J 0
(-3125 2725);
DISPLAY 0.872340 (-3125 2725);
DISPLAY INVISIBLE (-3125 2725);
FORCEPROP 1 LAST PATH I232
J 0
(-3452 2850);
DISPLAY 0.872340 (-3452 2850);
PAINT GREEN (-3452 2850);
DISPLAY INVISIBLE (-3452 2850);
FORCEADD TAP..1
(-3450 2650);
FORCEPROP 3 LASTPIN (-3500 2650) SIG_NAME M_I_CPU0_SB_DQS_DP<1>
J 0
(-3490 2660);
DISPLAY 0.659574 (-3490 2660);
PAINT MONO (-3490 2660);
DISPLAY INVISIBLE (-3490 2660);
FORCEPROP 1 LASTPIN (-3500 2650) BN 1
J 0
(-3512 2658);
DISPLAY 0.489362 (-3512 2658);
PAINT GREEN (-3512 2658);
FORCEPROP 2 LAST CDS_LIB mstr_standard
J 0
(-3450 2650);
DISPLAY 0.723404 (-3450 2650);
PAINT MONO (-3450 2650);
DISPLAY INVISIBLE (-3450 2650);
FORCEPROP 1 LAST BODY_TYPE PLUMBING
J 0
(-3450 2700);
DISPLAY 0.872340 (-3450 2700);
PAINT GREEN (-3450 2700);
DISPLAY INVISIBLE (-3450 2700);
FORCEPROP 1 LAST HDL_TAP TRUE
J 0
(-3125 2525);
DISPLAY 0.872340 (-3125 2525);
DISPLAY INVISIBLE (-3125 2525);
FORCEPROP 1 LAST PATH I233
J 0
(-3452 2650);
DISPLAY 0.872340 (-3452 2650);
PAINT GREEN (-3452 2650);
DISPLAY INVISIBLE (-3452 2650);
FORCEADD TAP..1
(-3450 2750);
FORCEPROP 3 LASTPIN (-3500 2750) SIG_NAME M_I_CPU0_SB_DQS_DP<2>
J 0
(-3490 2760);
DISPLAY 0.659574 (-3490 2760);
PAINT MONO (-3490 2760);
DISPLAY INVISIBLE (-3490 2760);
FORCEPROP 1 LASTPIN (-3500 2750) BN 2
J 0
(-3512 2758);
DISPLAY 0.489362 (-3512 2758);
PAINT GREEN (-3512 2758);
FORCEPROP 2 LAST CDS_LIB mstr_standard
J 0
(-3450 2750);
DISPLAY 0.723404 (-3450 2750);
PAINT MONO (-3450 2750);
DISPLAY INVISIBLE (-3450 2750);
FORCEPROP 1 LAST BODY_TYPE PLUMBING
J 0
(-3450 2800);
DISPLAY 0.872340 (-3450 2800);
PAINT GREEN (-3450 2800);
DISPLAY INVISIBLE (-3450 2800);
FORCEPROP 1 LAST HDL_TAP TRUE
J 0
(-3125 2625);
DISPLAY 0.872340 (-3125 2625);
DISPLAY INVISIBLE (-3125 2625);
FORCEPROP 1 LAST PATH I234
J 0
(-3452 2750);
DISPLAY 0.872340 (-3452 2750);
PAINT GREEN (-3452 2750);
DISPLAY INVISIBLE (-3452 2750);
FORCEADD TAP..1
(-3450 2550);
FORCEPROP 3 LASTPIN (-3500 2550) SIG_NAME M_I_CPU0_SB_DQS_DP<0>
J 0
(-3490 2560);
DISPLAY 0.659574 (-3490 2560);
PAINT MONO (-3490 2560);
DISPLAY INVISIBLE (-3490 2560);
FORCEPROP 1 LASTPIN (-3500 2550) BN 0
J 0
(-3512 2558);
DISPLAY 0.489362 (-3512 2558);
PAINT GREEN (-3512 2558);
FORCEPROP 2 LAST CDS_LIB mstr_standard
J 0
(-3450 2550);
DISPLAY 0.723404 (-3450 2550);
PAINT MONO (-3450 2550);
DISPLAY INVISIBLE (-3450 2550);
FORCEPROP 1 LAST BODY_TYPE PLUMBING
J 0
(-3450 2600);
DISPLAY 0.872340 (-3450 2600);
PAINT GREEN (-3450 2600);
DISPLAY INVISIBLE (-3450 2600);
FORCEPROP 1 LAST HDL_TAP TRUE
J 0
(-3125 2425);
DISPLAY 0.872340 (-3125 2425);
DISPLAY INVISIBLE (-3125 2425);
FORCEPROP 1 LAST PATH I235
J 0
(-3452 2550);
DISPLAY 0.872340 (-3452 2550);
PAINT GREEN (-3452 2550);
DISPLAY INVISIBLE (-3452 2550);
FORCEADD SCONN288_DDR506112002KQ..2
(-4400 3500);
FORCEPROP 1 LAST LOCATION J18
J 0
(-5000 4825);
DISPLAY 0.468085 (-5000 4825);
PAINT SKYBLUE (-5000 4825);
FORCEPROP 0 LAST $SEC 2
J 0
(-4850 4975);
DISPLAY 0.680851 (-4850 4975);
PAINT MONO (-4850 4975);
DISPLAY INVISIBLE (-4850 4975);
FORCEPROP 0 LAST CDS_SEC 2
J 0
(-4850 4975);
DISPLAY 1.021277 (-4850 4975);
DISPLAY INVISIBLE (-4850 4975);
FORCEPROP 0 LASTPIN (-3650 3550) $PN 12
J 0
(-3640 3560);
DISPLAY 0.680851 (-3640 3560);
PAINT MONO (-3640 3560);
FORCEPROP 0 LASTPIN (-3650 3600) $PN 11
J 0
(-3640 3610);
DISPLAY 0.680851 (-3640 3610);
PAINT MONO (-3640 3610);
FORCEPROP 0 LASTPIN (-3650 2500) $PN 105
J 0
(-3640 2510);
DISPLAY 0.680851 (-3640 2510);
PAINT MONO (-3640 2510);
FORCEPROP 0 LASTPIN (-3650 2550) $PN 104
J 0
(-3640 2560);
DISPLAY 0.680851 (-3640 2560);
PAINT MONO (-3640 2560);
FORCEPROP 0 LASTPIN (-3650 3650) $PN 23
J 0
(-3640 3660);
DISPLAY 0.680851 (-3640 3660);
PAINT MONO (-3640 3660);
FORCEPROP 0 LASTPIN (-3650 3700) $PN 22
J 0
(-3640 3710);
DISPLAY 0.680851 (-3640 3710);
PAINT MONO (-3640 3710);
FORCEPROP 0 LASTPIN (-3650 2600) $PN 116
J 0
(-3640 2610);
DISPLAY 0.680851 (-3640 2610);
PAINT MONO (-3640 2610);
FORCEPROP 0 LASTPIN (-3650 2650) $PN 115
J 0
(-3640 2660);
DISPLAY 0.680851 (-3640 2660);
PAINT MONO (-3640 2660);
FORCEPROP 0 LASTPIN (-3650 3750) $PN 34
J 0
(-3640 3760);
DISPLAY 0.680851 (-3640 3760);
PAINT MONO (-3640 3760);
FORCEPROP 0 LASTPIN (-3650 3800) $PN 33
J 0
(-3640 3810);
DISPLAY 0.680851 (-3640 3810);
PAINT MONO (-3640 3810);
FORCEPROP 0 LASTPIN (-3650 2700) $PN 127
J 0
(-3640 2710);
DISPLAY 0.680851 (-3640 2710);
PAINT MONO (-3640 2710);
FORCEPROP 0 LASTPIN (-3650 2750) $PN 126
J 0
(-3640 2760);
DISPLAY 0.680851 (-3640 2760);
PAINT MONO (-3640 2760);
FORCEPROP 0 LASTPIN (-3650 3850) $PN 45
J 0
(-3640 3860);
DISPLAY 0.680851 (-3640 3860);
PAINT MONO (-3640 3860);
FORCEPROP 0 LASTPIN (-3650 3900) $PN 44
J 0
(-3640 3910);
DISPLAY 0.680851 (-3640 3910);
PAINT MONO (-3640 3910);
FORCEPROP 0 LASTPIN (-3650 2800) $PN 138
J 0
(-3640 2810);
DISPLAY 0.680851 (-3640 2810);
PAINT MONO (-3640 2810);
FORCEPROP 0 LASTPIN (-3650 2850) $PN 137
J 0
(-3640 2860);
DISPLAY 0.680851 (-3640 2860);
PAINT MONO (-3640 2860);
FORCEPROP 0 LASTPIN (-3650 3950) $PN 56
J 0
(-3640 3960);
DISPLAY 0.680851 (-3640 3960);
PAINT MONO (-3640 3960);
FORCEPROP 0 LASTPIN (-3650 4000) $PN 55
J 0
(-3640 4010);
DISPLAY 0.680851 (-3640 4010);
PAINT MONO (-3640 4010);
FORCEPROP 0 LASTPIN (-3650 2900) $PN 238
J 0
(-3640 2910);
DISPLAY 0.680851 (-3640 2910);
PAINT MONO (-3640 2910);
FORCEPROP 0 LASTPIN (-3650 2950) $PN 239
J 0
(-3640 2960);
DISPLAY 0.680851 (-3640 2960);
PAINT MONO (-3640 2960);
FORCEPROP 0 LASTPIN (-3650 4050) $PN 156
J 0
(-3640 4060);
DISPLAY 0.680851 (-3640 4060);
PAINT MONO (-3640 4060);
FORCEPROP 0 LASTPIN (-3650 4100) $PN 157
J 0
(-3640 4110);
DISPLAY 0.680851 (-3640 4110);
PAINT MONO (-3640 4110);
FORCEPROP 0 LASTPIN (-3650 3000) $PN 249
J 0
(-3640 3010);
DISPLAY 0.680851 (-3640 3010);
PAINT MONO (-3640 3010);
FORCEPROP 0 LASTPIN (-3650 3050) $PN 250
J 0
(-3640 3060);
DISPLAY 0.680851 (-3640 3060);
PAINT MONO (-3640 3060);
FORCEPROP 0 LASTPIN (-3650 4150) $PN 167
J 0
(-3640 4160);
DISPLAY 0.680851 (-3640 4160);
PAINT MONO (-3640 4160);
FORCEPROP 0 LASTPIN (-3650 4200) $PN 168
J 0
(-3640 4210);
DISPLAY 0.680851 (-3640 4210);
PAINT MONO (-3640 4210);
FORCEPROP 0 LASTPIN (-3650 3100) $PN 260
J 0
(-3640 3110);
DISPLAY 0.680851 (-3640 3110);
PAINT MONO (-3640 3110);
FORCEPROP 0 LASTPIN (-3650 3150) $PN 261
J 0
(-3640 3160);
DISPLAY 0.680851 (-3640 3160);
PAINT MONO (-3640 3160);
FORCEPROP 0 LASTPIN (-3650 4250) $PN 178
J 0
(-3640 4260);
DISPLAY 0.680851 (-3640 4260);
PAINT MONO (-3640 4260);
FORCEPROP 0 LASTPIN (-3650 4300) $PN 179
J 0
(-3640 4310);
DISPLAY 0.680851 (-3640 4310);
PAINT MONO (-3640 4310);
FORCEPROP 0 LASTPIN (-3650 3200) $PN 271
J 0
(-3640 3210);
DISPLAY 0.680851 (-3640 3210);
PAINT MONO (-3640 3210);
FORCEPROP 0 LASTPIN (-3650 3250) $PN 272
J 0
(-3640 3260);
DISPLAY 0.680851 (-3640 3260);
PAINT MONO (-3640 3260);
FORCEPROP 0 LASTPIN (-3650 4350) $PN 189
J 0
(-3640 4360);
DISPLAY 0.680851 (-3640 4360);
PAINT MONO (-3640 4360);
FORCEPROP 0 LASTPIN (-3650 4400) $PN 190
J 0
(-3640 4410);
DISPLAY 0.680851 (-3640 4410);
PAINT MONO (-3640 4410);
FORCEPROP 0 LASTPIN (-3650 3300) $PN 282
J 0
(-3640 3310);
DISPLAY 0.680851 (-3640 3310);
PAINT MONO (-3640 3310);
FORCEPROP 0 LASTPIN (-3650 3350) $PN 283
J 0
(-3640 3360);
DISPLAY 0.680851 (-3640 3360);
PAINT MONO (-3640 3360);
FORCEPROP 0 LASTPIN (-3650 4450) $PN 200
J 0
(-3640 4460);
DISPLAY 0.680851 (-3640 4460);
PAINT MONO (-3640 4460);
FORCEPROP 0 LASTPIN (-3650 4500) $PN 201
J 0
(-3640 4510);
DISPLAY 0.680851 (-3640 4510);
PAINT MONO (-3640 4510);
FORCEPROP 0 LASTPIN (-3650 3400) $PN 94
J 0
(-3640 3410);
DISPLAY 0.680851 (-3640 3410);
PAINT MONO (-3640 3410);
FORCEPROP 0 LASTPIN (-3650 3450) $PN 93
J 0
(-3640 3460);
DISPLAY 0.680851 (-3640 3460);
PAINT MONO (-3640 3460);
FORCEPROP 2 LAST PART_TYPE SMLF
J 0
(-4850 4925);
DISPLAY 1.021277 (-4850 4925);
FORCEPROP 1 LAST MATERIAL IO
J 0
(-5000 4675);
DISPLAY 0.468085 (-5000 4675);
PAINT SKYBLUE (-5000 4675);
FORCEPROP 2 LAST VALUE SCONN288_DDR506112002KQ
J 0
(-4850 4875);
DISPLAY 0.489362 (-4850 4875);
PAINT SKYBLUE (-4850 4875);
FORCEPROP 1 LAST PART_NUMBER DFHST8FS479
J 0
(-5000 4750);
DISPLAY 0.468085 (-5000 4750);
PAINT SKYBLUE (-5000 4750);
FORCEPROP 1 LAST CDS_LMAN_SYM_OUTLINE -600,1150,600,-1150
J 0
(-4400 3500);
DISPLAY 0.468085 (-4400 3500);
PAINT GREEN (-4400 3500);
DISPLAY INVISIBLE (-4400 3500);
FORCEPROP 1 LAST PATH I236
J 0
(-4400 3500);
DISPLAY 0.723404 (-4400 3500);
PAINT GREEN (-4400 3500);
DISPLAY INVISIBLE (-4400 3500);
FORCEPROP 1 LAST NEEDS_NO_SIZE TRUE
J 0
(-4400 3500);
DISPLAY 0.723404 (-4400 3500);
PAINT GREEN (-4400 3500);
DISPLAY INVISIBLE (-4400 3500);
FORCEPROP 2 LAST CDS_LIB pure_quanta
J 0
(-4400 3500);
DISPLAY INVISIBLE (-4400 3500);
FORCEADD GND..1
(-2825 5550);
FORCEPROP 3 LASTPIN (-2825 5600) SIG_NAME GND\g
J 0
(-2815 5610);
DISPLAY 0.659574 (-2815 5610);
PAINT MONO (-2815 5610);
DISPLAY INVISIBLE (-2815 5610);
FORCEPROP 2 LAST CDS_LIB pure_quanta_power
J 0
(-2825 5550);
DISPLAY INVISIBLE (-2825 5550);
FORCEPROP 2 LAST BOM_COST MEM
J 0
(-2800 5675);
DISPLAY 0.659574 (-2800 5675);
DISPLAY INVISIBLE (-2800 5675);
FORCEPROP 1 LAST SIZE 1B
J 0
(-2750 5500);
DISPLAY 0.723404 (-2750 5500);
PAINT GREEN (-2750 5500);
DISPLAY INVISIBLE (-2750 5500);
FORCEPROP 1 LAST PATH I237
J 0
(-2750 5550);
DISPLAY 0.872340 (-2750 5550);
PAINT AQUA (-2750 5550);
DISPLAY INVISIBLE (-2750 5550);
FORCEPROP 2 LAST ROOM MEM_EFGH_DECOUPLING_CAPS
J 0
(-2800 5625);
DISPLAY 0.659574 (-2800 5625);
PAINT RED (-2800 5625);
DISPLAY INVISIBLE (-2800 5625);
FORCEPROP 1 LAST HDL_POWER GND
J 0
(-2825 5700);
DISPLAY 0.723404 (-2825 5700);
PAINT GREEN (-2825 5700);
DISPLAY INVISIBLE (-2825 5700);
FORCEADD Q_CAP..1
R 2
(-2825 5900);
FORCEPROP 1 LAST LOCATION C162
J 2
(-2875 6000);
DISPLAY 0.489362 (-2875 6000);
PAINT SKYBLUE (-2875 6000);
FORCEPROP 0 LAST $SEC 1
J 0
(-2875 6050);
DISPLAY 0.680851 (-2875 6050);
PAINT MONO (-2875 6050);
DISPLAY INVISIBLE (-2875 6050);
FORCEPROP 0 LAST CDS_SEC 1
J 0
(-2875 6050);
DISPLAY 0.680851 (-2875 6050);
DISPLAY INVISIBLE (-2875 6050);
FORCEPROP 1 LASTPIN (-2825 6000) $PN 1
J 2
(-2835 5980);
DISPLAY 0.489362 (-2835 5980);
PAINT MONO (-2835 5980);
FORCEPROP 1 LASTPIN (-2825 5800) $PN 2
J 2
(-2835 5780);
DISPLAY 0.489362 (-2835 5780);
PAINT MONO (-2835 5780);
FORCEPROP 1 LAST MATERIAL X6S
J 2
(-2875 5800);
DISPLAY 0.489362 (-2875 5800);
PAINT SKYBLUE (-2875 5800);
FORCEPROP 1 LAST TOLERANCE 10%
J 2
(-2875 5850);
DISPLAY 0.489362 (-2875 5850);
PAINT SKYBLUE (-2875 5850);
FORCEPROP 1 LAST VALUE 10UF
J 2
(-2875 5950);
DISPLAY 0.489362 (-2875 5950);
PAINT SKYBLUE (-2875 5950);
FORCEPROP 1 LAST PART_NUMBER CH6104KEA00
J 2
(-2875 5750);
DISPLAY 0.489362 (-2875 5750);
PAINT SKYBLUE (-2875 5750);
FORCEPROP 1 LAST VOLTAGE 25V
J 2
(-2875 5900);
DISPLAY 0.489362 (-2875 5900);
PAINT SKYBLUE (-2875 5900);
FORCEPROP 1 LAST PACK_TYPE C0805
J 2
(-2875 5700);
DISPLAY 0.489362 (-2875 5700);
PAINT SKYBLUE (-2875 5700);
FORCEPROP 0 LAST BOM_COST MEM
J 2
(-2880 6045);
DISPLAY 0.595745 (-2880 6045);
PAINT MONO (-2880 6045);
DISPLAY INVISIBLE (-2880 6045);
FORCEPROP 2 LAST CDS_LIB pure_quanta
J 0
(-2825 5900);
DISPLAY INVISIBLE (-2825 5900);
FORCEPROP 1 LAST PATH I238
J 2
(-2875 6050);
DISPLAY 0.978723 (-2875 6050);
PAINT WHITE (-2875 6050);
DISPLAY INVISIBLE (-2875 6050);
FORCEPROP 0 LAST ROOM MEM_CH_A_CPU0_DIMM1
J 2
(-2880 6045);
DISPLAY 0.595745 (-2880 6045);
PAINT RED (-2880 6045);
DISPLAY INVISIBLE (-2880 6045);
FORCEADD Q_CAP..1
R 2
(-2250 5900);
FORCEPROP 1 LAST LOCATION C163
J 2
(-2300 6000);
DISPLAY 0.489362 (-2300 6000);
PAINT SKYBLUE (-2300 6000);
FORCEPROP 0 LAST $SEC 1
J 0
(-2300 6050);
DISPLAY 0.680851 (-2300 6050);
PAINT MONO (-2300 6050);
DISPLAY INVISIBLE (-2300 6050);
FORCEPROP 0 LAST CDS_SEC 1
J 0
(-2300 6050);
DISPLAY 0.680851 (-2300 6050);
DISPLAY INVISIBLE (-2300 6050);
FORCEPROP 1 LASTPIN (-2250 6000) $PN 1
J 2
(-2260 5980);
DISPLAY 0.489362 (-2260 5980);
PAINT MONO (-2260 5980);
FORCEPROP 1 LASTPIN (-2250 5800) $PN 2
J 2
(-2260 5780);
DISPLAY 0.489362 (-2260 5780);
PAINT MONO (-2260 5780);
FORCEPROP 1 LAST MATERIAL X6S
J 2
(-2300 5800);
DISPLAY 0.489362 (-2300 5800);
PAINT SKYBLUE (-2300 5800);
FORCEPROP 1 LAST TOLERANCE 10%
J 2
(-2300 5850);
DISPLAY 0.489362 (-2300 5850);
PAINT SKYBLUE (-2300 5850);
FORCEPROP 1 LAST VALUE 10UF
J 2
(-2300 5950);
DISPLAY 0.489362 (-2300 5950);
PAINT SKYBLUE (-2300 5950);
FORCEPROP 1 LAST PART_NUMBER CH6104KEA00
J 2
(-2300 5750);
DISPLAY 0.489362 (-2300 5750);
PAINT SKYBLUE (-2300 5750);
FORCEPROP 1 LAST VOLTAGE 25V
J 2
(-2300 5900);
DISPLAY 0.489362 (-2300 5900);
PAINT SKYBLUE (-2300 5900);
FORCEPROP 1 LAST PACK_TYPE C0805
J 2
(-2300 5700);
DISPLAY 0.489362 (-2300 5700);
PAINT SKYBLUE (-2300 5700);
FORCEPROP 0 LAST BOM_COST MEM
J 2
(-2305 6045);
DISPLAY 0.595745 (-2305 6045);
PAINT MONO (-2305 6045);
DISPLAY INVISIBLE (-2305 6045);
FORCEPROP 2 LAST CDS_LIB pure_quanta
J 0
(-2250 5900);
DISPLAY INVISIBLE (-2250 5900);
FORCEPROP 1 LAST PATH I239
J 2
(-2300 6050);
DISPLAY 0.978723 (-2300 6050);
PAINT WHITE (-2300 6050);
DISPLAY INVISIBLE (-2300 6050);
FORCEPROP 0 LAST ROOM MEM_CH_A_CPU0_DIMM1
J 2
(-2305 6045);
DISPLAY 0.595745 (-2305 6045);
PAINT RED (-2305 6045);
DISPLAY INVISIBLE (-2305 6045);
FORCEADD TAP..1
R 2
(-7700 3400);
FORCEPROP 3 LASTPIN (-7650 3400) SIG_NAME M_I_CPU0_SB_CB<3>
J 0
(-7640 3410);
DISPLAY 0.659574 (-7640 3410);
PAINT MONO (-7640 3410);
DISPLAY INVISIBLE (-7640 3410);
FORCEPROP 1 LASTPIN (-7650 3400) BN 3
J 2
(-7638 3408);
DISPLAY 0.489362 (-7638 3408);
PAINT GREEN (-7638 3408);
FORCEPROP 2 LAST CDS_LIB mstr_standard
J 0
(-7700 3400);
DISPLAY 0.723404 (-7700 3400);
PAINT MONO (-7700 3400);
DISPLAY INVISIBLE (-7700 3400);
FORCEPROP 1 LAST BODY_TYPE PLUMBING
J 2
(-7700 3450);
DISPLAY 0.872340 (-7700 3450);
PAINT GREEN (-7700 3450);
DISPLAY INVISIBLE (-7700 3450);
FORCEPROP 1 LAST HDL_TAP TRUE
J 2
(-8025 3275);
DISPLAY 0.872340 (-8025 3275);
DISPLAY INVISIBLE (-8025 3275);
FORCEPROP 1 LAST PATH I24
J 2
(-7698 3400);
DISPLAY 0.872340 (-7698 3400);
PAINT GREEN (-7698 3400);
DISPLAY INVISIBLE (-7698 3400);
FORCEADD UNIVERSAL_POWER..1
(-2825 6225);
FORCEPROP 3 LASTPIN (-2825 6175) SIG_NAME P12V_MEM_0\g
J 0
(-2815 6185);
DISPLAY 0.659574 (-2815 6185);
PAINT MONO (-2815 6185);
DISPLAY INVISIBLE (-2815 6185);
FORCEPROP 1 LAST HDL_POWER P12V_MEM_0
J 1
(-2850 6275);
DISPLAY 0.489362 (-2850 6275);
PAINT GREEN (-2850 6275);
FORCEPROP 2 LAST BOM_COST VR_SYSTEM
J 0
(-2825 6325);
DISPLAY 0.617021 (-2825 6325);
PAINT PURPLE (-2825 6325);
DISPLAY INVISIBLE (-2825 6325);
FORCEPROP 2 LAST CDS_LIB pure_quanta_power
J 0
(-2825 6225);
DISPLAY INVISIBLE (-2825 6225);
FORCEPROP 1 LAST PATH I240
J 0
(-2775 6250);
DISPLAY 0.872340 (-2775 6250);
PAINT AQUA (-2775 6250);
DISPLAY INVISIBLE (-2775 6250);
FORCEADD OFFPAGE..1
(-8300 2750);
FORCEPROP 2 LAST $XR5 96 
J 0
(-9002 2750);
DISPLAY 0.638298 (-9002 2750);
PAINT MONO (-9002 2750);
FORCEPROP 2 LAST $XR4 95 
J 0
(-8912 2750);
DISPLAY 0.638298 (-8912 2750);
PAINT MONO (-8912 2750);
FORCEPROP 2 LAST $XR3 94 
J 0
(-8822 2750);
DISPLAY 0.638298 (-8822 2750);
PAINT MONO (-8822 2750);
FORCEPROP 2 LAST $XR2 92 
J 0
(-8732 2750);
DISPLAY 0.638298 (-8732 2750);
PAINT MONO (-8732 2750);
FORCEPROP 2 LAST $XR1 91 
J 0
(-8642 2750);
DISPLAY 0.638298 (-8642 2750);
PAINT MONO (-8642 2750);
FORCEPROP 2 LAST $XR0 136 
J 0
(-8552 2750);
DISPLAY 0.638298 (-8552 2750);
PAINT MONO (-8552 2750);
FORCEPROP 2 LAST PATH I241
J 0
(-8575 2800);
DISPLAY 0.680851 (-8575 2800);
DISPLAY INVISIBLE (-8575 2800);
FORCEPROP 1 LAST COMMENT_BODY TRUE
J 0
(-8175 2650);
DISPLAY 0.872340 (-8175 2650);
PAINT GREEN (-8175 2650);
DISPLAY INVISIBLE (-8175 2650);
FORCEPROP 1 LAST OFFPAGE TRUE
J 0
(-7975 2625);
DISPLAY 0.872340 (-7975 2625);
PAINT GREEN (-7975 2625);
DISPLAY INVISIBLE (-7975 2625);
FORCEPROP 2 LAST CDS_LIB mstr_standard
J 0
(-8300 2750);
DISPLAY 0.808511 (-8300 2750);
DISPLAY INVISIBLE (-8300 2750);
FORCEADD Q_RES..1
(-7750 2750);
FORCEPROP 1 LAST $LOCATION R1576
J 0
(-7800 2775);
DISPLAY 0.510638 (-7800 2775);
PAINT SKYBLUE (-7800 2775);
FORCEPROP 0 LAST CDS_LOCATION R1576
J 0
(-7800 2850);
DISPLAY 0.680851 (-7800 2850);
DISPLAY INVISIBLE (-7800 2850);
FORCEPROP 0 LAST $SEC 1
J 0
(-7800 2850);
DISPLAY 0.680851 (-7800 2850);
PAINT MONO (-7800 2850);
DISPLAY INVISIBLE (-7800 2850);
FORCEPROP 0 LAST CDS_SEC 1
J 0
(-7800 2850);
DISPLAY 0.680851 (-7800 2850);
DISPLAY INVISIBLE (-7800 2850);
FORCEPROP 1 LASTPIN (-7850 2750) $PN 1
J 0
(-7838 2762);
DISPLAY 0.787234 (-7838 2762);
PAINT MONO (-7838 2762);
FORCEPROP 1 LASTPIN (-7650 2750) $PN 2
J 0
(-7688 2762);
DISPLAY 0.787234 (-7688 2762);
PAINT MONO (-7688 2762);
FORCEPROP 1 LAST VALUE 49.9
J 2
(-7600 2800);
DISPLAY 0.510638 (-7600 2800);
PAINT SKYBLUE (-7600 2800);
FORCEPROP 2 LAST CDS_LIB pure_quanta
J 0
(-7750 2750);
DISPLAY INVISIBLE (-7750 2750);
FORCEPROP 1 LAST PATH I242
J 0
(-7800 2900);
DISPLAY 0.978723 (-7800 2900);
PAINT WHITE (-7800 2900);
DISPLAY INVISIBLE (-7800 2900);
FORCEPROP 1 LAST MATERIAL CHIP
J 0
(-7750 2600);
DISPLAY 0.978723 (-7750 2600);
DISPLAY INVISIBLE (-7750 2600);
FORCEPROP 1 LAST PACK_TYPE 0402LF
J 0
(-7500 2600);
DISPLAY 0.978723 (-7500 2600);
DISPLAY INVISIBLE (-7500 2600);
FORCEPROP 1 LAST WATTAGE 1/16W
J 2
(-7775 2600);
DISPLAY 0.978723 (-7775 2600);
DISPLAY INVISIBLE (-7775 2600);
FORCEPROP 1 LAST TOLERANCE 1%
J 0
(-7750 2650);
DISPLAY 0.978723 (-7750 2650);
DISPLAY INVISIBLE (-7750 2650);
FORCEPROP 1 LAST PART_NUMBER CS04992FB07
J 0
(-7800 2850);
DISPLAY 0.978723 (-7800 2850);
DISPLAY INVISIBLE (-7800 2850);
FORCEADD TAP..1
R 2
(-7700 3300);
FORCEPROP 3 LASTPIN (-7650 3300) SIG_NAME M_I_CPU0_SB_CB<1>
J 0
(-7640 3310);
DISPLAY 0.659574 (-7640 3310);
PAINT MONO (-7640 3310);
DISPLAY INVISIBLE (-7640 3310);
FORCEPROP 1 LASTPIN (-7650 3300) BN 1
J 2
(-7638 3308);
DISPLAY 0.489362 (-7638 3308);
PAINT GREEN (-7638 3308);
FORCEPROP 2 LAST CDS_LIB mstr_standard
J 0
(-7700 3300);
DISPLAY 0.723404 (-7700 3300);
PAINT MONO (-7700 3300);
DISPLAY INVISIBLE (-7700 3300);
FORCEPROP 1 LAST BODY_TYPE PLUMBING
J 2
(-7700 3350);
DISPLAY 0.872340 (-7700 3350);
PAINT GREEN (-7700 3350);
DISPLAY INVISIBLE (-7700 3350);
FORCEPROP 1 LAST HDL_TAP TRUE
J 2
(-8025 3175);
DISPLAY 0.872340 (-8025 3175);
DISPLAY INVISIBLE (-8025 3175);
FORCEPROP 1 LAST PATH I25
J 2
(-7698 3300);
DISPLAY 0.872340 (-7698 3300);
PAINT GREEN (-7698 3300);
DISPLAY INVISIBLE (-7698 3300);
FORCEADD TAP..1
R 2
(-7700 3250);
FORCEPROP 3 LASTPIN (-7650 3250) SIG_NAME M_I_CPU0_SB_CB<0>
J 0
(-7640 3260);
DISPLAY 0.659574 (-7640 3260);
PAINT MONO (-7640 3260);
DISPLAY INVISIBLE (-7640 3260);
FORCEPROP 1 LASTPIN (-7650 3250) BN 0
J 2
(-7638 3258);
DISPLAY 0.489362 (-7638 3258);
PAINT GREEN (-7638 3258);
FORCEPROP 2 LAST CDS_LIB mstr_standard
J 0
(-7700 3250);
DISPLAY 0.723404 (-7700 3250);
PAINT MONO (-7700 3250);
DISPLAY INVISIBLE (-7700 3250);
FORCEPROP 1 LAST BODY_TYPE PLUMBING
J 2
(-7700 3300);
DISPLAY 0.872340 (-7700 3300);
PAINT GREEN (-7700 3300);
DISPLAY INVISIBLE (-7700 3300);
FORCEPROP 1 LAST HDL_TAP TRUE
J 2
(-8025 3125);
DISPLAY 0.872340 (-8025 3125);
DISPLAY INVISIBLE (-8025 3125);
FORCEPROP 1 LAST PATH I26
J 2
(-7698 3250);
DISPLAY 0.872340 (-7698 3250);
PAINT GREEN (-7698 3250);
DISPLAY INVISIBLE (-7698 3250);
FORCEADD TAP..1
R 2
(-7700 3450);
FORCEPROP 3 LASTPIN (-7650 3450) SIG_NAME M_I_CPU0_SB_CB<4>
J 0
(-7640 3460);
DISPLAY 0.659574 (-7640 3460);
PAINT MONO (-7640 3460);
DISPLAY INVISIBLE (-7640 3460);
FORCEPROP 1 LASTPIN (-7650 3450) BN 4
J 2
(-7638 3458);
DISPLAY 0.489362 (-7638 3458);
PAINT GREEN (-7638 3458);
FORCEPROP 2 LAST CDS_LIB mstr_standard
J 0
(-7700 3450);
DISPLAY 0.723404 (-7700 3450);
PAINT MONO (-7700 3450);
DISPLAY INVISIBLE (-7700 3450);
FORCEPROP 1 LAST BODY_TYPE PLUMBING
J 2
(-7700 3500);
DISPLAY 0.872340 (-7700 3500);
PAINT GREEN (-7700 3500);
DISPLAY INVISIBLE (-7700 3500);
FORCEPROP 1 LAST HDL_TAP TRUE
J 2
(-8025 3325);
DISPLAY 0.872340 (-8025 3325);
DISPLAY INVISIBLE (-8025 3325);
FORCEPROP 1 LAST PATH I27
J 2
(-7698 3450);
DISPLAY 0.872340 (-7698 3450);
PAINT GREEN (-7698 3450);
DISPLAY INVISIBLE (-7698 3450);
FORCEADD TAP..1
R 2
(-7700 3500);
FORCEPROP 3 LASTPIN (-7650 3500) SIG_NAME M_I_CPU0_SB_CB<5>
J 0
(-7640 3510);
DISPLAY 0.659574 (-7640 3510);
PAINT MONO (-7640 3510);
DISPLAY INVISIBLE (-7640 3510);
FORCEPROP 1 LASTPIN (-7650 3500) BN 5
J 2
(-7638 3508);
DISPLAY 0.489362 (-7638 3508);
PAINT GREEN (-7638 3508);
FORCEPROP 2 LAST CDS_LIB mstr_standard
J 0
(-7700 3500);
DISPLAY 0.723404 (-7700 3500);
PAINT MONO (-7700 3500);
DISPLAY INVISIBLE (-7700 3500);
FORCEPROP 1 LAST BODY_TYPE PLUMBING
J 2
(-7700 3550);
DISPLAY 0.872340 (-7700 3550);
PAINT GREEN (-7700 3550);
DISPLAY INVISIBLE (-7700 3550);
FORCEPROP 1 LAST HDL_TAP TRUE
J 2
(-8025 3375);
DISPLAY 0.872340 (-8025 3375);
DISPLAY INVISIBLE (-8025 3375);
FORCEPROP 1 LAST PATH I28
J 2
(-7698 3500);
DISPLAY 0.872340 (-7698 3500);
PAINT GREEN (-7698 3500);
DISPLAY INVISIBLE (-7698 3500);
FORCEADD TAP..1
R 2
(-7700 3550);
FORCEPROP 3 LASTPIN (-7650 3550) SIG_NAME M_I_CPU0_SB_CB<6>
J 0
(-7640 3560);
DISPLAY 0.659574 (-7640 3560);
PAINT MONO (-7640 3560);
DISPLAY INVISIBLE (-7640 3560);
FORCEPROP 1 LASTPIN (-7650 3550) BN 6
J 2
(-7638 3558);
DISPLAY 0.489362 (-7638 3558);
PAINT GREEN (-7638 3558);
FORCEPROP 2 LAST CDS_LIB mstr_standard
J 0
(-7700 3550);
DISPLAY 0.723404 (-7700 3550);
PAINT MONO (-7700 3550);
DISPLAY INVISIBLE (-7700 3550);
FORCEPROP 1 LAST BODY_TYPE PLUMBING
J 2
(-7700 3600);
DISPLAY 0.872340 (-7700 3600);
PAINT GREEN (-7700 3600);
DISPLAY INVISIBLE (-7700 3600);
FORCEPROP 1 LAST HDL_TAP TRUE
J 2
(-8025 3425);
DISPLAY 0.872340 (-8025 3425);
DISPLAY INVISIBLE (-8025 3425);
FORCEPROP 1 LAST PATH I29
J 2
(-7698 3550);
DISPLAY 0.872340 (-7698 3550);
PAINT GREEN (-7698 3550);
DISPLAY INVISIBLE (-7698 3550);
FORCEADD TAP..1
R 2
(-7700 3600);
FORCEPROP 3 LASTPIN (-7650 3600) SIG_NAME M_I_CPU0_SB_CB<7>
J 0
(-7640 3610);
DISPLAY 0.659574 (-7640 3610);
PAINT MONO (-7640 3610);
DISPLAY INVISIBLE (-7640 3610);
FORCEPROP 1 LASTPIN (-7650 3600) BN 7
J 2
(-7638 3608);
DISPLAY 0.489362 (-7638 3608);
PAINT GREEN (-7638 3608);
FORCEPROP 2 LAST CDS_LIB mstr_standard
J 0
(-7700 3600);
DISPLAY 0.723404 (-7700 3600);
PAINT MONO (-7700 3600);
DISPLAY INVISIBLE (-7700 3600);
FORCEPROP 1 LAST BODY_TYPE PLUMBING
J 2
(-7700 3650);
DISPLAY 0.872340 (-7700 3650);
PAINT GREEN (-7700 3650);
DISPLAY INVISIBLE (-7700 3650);
FORCEPROP 1 LAST HDL_TAP TRUE
J 2
(-8025 3475);
DISPLAY 0.872340 (-8025 3475);
DISPLAY INVISIBLE (-8025 3475);
FORCEPROP 1 LAST PATH I30
J 2
(-7698 3600);
DISPLAY 0.872340 (-7698 3600);
PAINT GREEN (-7698 3600);
DISPLAY INVISIBLE (-7698 3600);
FORCEADD TAP..1
R 2
(-7700 3700);
FORCEPROP 3 LASTPIN (-7650 3700) SIG_NAME M_I_CPU0_SA_CB<0>
J 0
(-7640 3710);
DISPLAY 0.659574 (-7640 3710);
PAINT MONO (-7640 3710);
DISPLAY INVISIBLE (-7640 3710);
FORCEPROP 1 LASTPIN (-7650 3700) BN 0
J 2
(-7638 3708);
DISPLAY 0.489362 (-7638 3708);
PAINT GREEN (-7638 3708);
FORCEPROP 2 LAST CDS_LIB mstr_standard
J 0
(-7700 3700);
DISPLAY 0.723404 (-7700 3700);
PAINT MONO (-7700 3700);
DISPLAY INVISIBLE (-7700 3700);
FORCEPROP 1 LAST BODY_TYPE PLUMBING
J 2
(-7700 3750);
DISPLAY 0.872340 (-7700 3750);
PAINT GREEN (-7700 3750);
DISPLAY INVISIBLE (-7700 3750);
FORCEPROP 1 LAST HDL_TAP TRUE
J 2
(-8025 3575);
DISPLAY 0.872340 (-8025 3575);
DISPLAY INVISIBLE (-8025 3575);
FORCEPROP 1 LAST PATH I31
J 2
(-7698 3700);
DISPLAY 0.872340 (-7698 3700);
PAINT GREEN (-7698 3700);
DISPLAY INVISIBLE (-7698 3700);
FORCEADD TAP..1
R 2
(-7700 3750);
FORCEPROP 3 LASTPIN (-7650 3750) SIG_NAME M_I_CPU0_SA_CB<1>
J 0
(-7640 3760);
DISPLAY 0.659574 (-7640 3760);
PAINT MONO (-7640 3760);
DISPLAY INVISIBLE (-7640 3760);
FORCEPROP 1 LASTPIN (-7650 3750) BN 1
J 2
(-7638 3758);
DISPLAY 0.489362 (-7638 3758);
PAINT GREEN (-7638 3758);
FORCEPROP 2 LAST CDS_LIB mstr_standard
J 0
(-7700 3750);
DISPLAY 0.723404 (-7700 3750);
PAINT MONO (-7700 3750);
DISPLAY INVISIBLE (-7700 3750);
FORCEPROP 1 LAST BODY_TYPE PLUMBING
J 2
(-7700 3800);
DISPLAY 0.872340 (-7700 3800);
PAINT GREEN (-7700 3800);
DISPLAY INVISIBLE (-7700 3800);
FORCEPROP 1 LAST HDL_TAP TRUE
J 2
(-8025 3625);
DISPLAY 0.872340 (-8025 3625);
DISPLAY INVISIBLE (-8025 3625);
FORCEPROP 1 LAST PATH I32
J 2
(-7698 3750);
DISPLAY 0.872340 (-7698 3750);
PAINT GREEN (-7698 3750);
DISPLAY INVISIBLE (-7698 3750);
FORCEADD TAP..1
R 2
(-7700 3800);
FORCEPROP 3 LASTPIN (-7650 3800) SIG_NAME M_I_CPU0_SA_CB<2>
J 0
(-7640 3810);
DISPLAY 0.659574 (-7640 3810);
PAINT MONO (-7640 3810);
DISPLAY INVISIBLE (-7640 3810);
FORCEPROP 1 LASTPIN (-7650 3800) BN 2
J 2
(-7638 3808);
DISPLAY 0.489362 (-7638 3808);
PAINT GREEN (-7638 3808);
FORCEPROP 2 LAST CDS_LIB mstr_standard
J 0
(-7700 3800);
DISPLAY 0.723404 (-7700 3800);
PAINT MONO (-7700 3800);
DISPLAY INVISIBLE (-7700 3800);
FORCEPROP 1 LAST BODY_TYPE PLUMBING
J 2
(-7700 3850);
DISPLAY 0.872340 (-7700 3850);
PAINT GREEN (-7700 3850);
DISPLAY INVISIBLE (-7700 3850);
FORCEPROP 1 LAST HDL_TAP TRUE
J 2
(-8025 3675);
DISPLAY 0.872340 (-8025 3675);
DISPLAY INVISIBLE (-8025 3675);
FORCEPROP 1 LAST PATH I33
J 2
(-7698 3800);
DISPLAY 0.872340 (-7698 3800);
PAINT GREEN (-7698 3800);
DISPLAY INVISIBLE (-7698 3800);
FORCEADD TAP..1
R 2
(-7700 3850);
FORCEPROP 3 LASTPIN (-7650 3850) SIG_NAME M_I_CPU0_SA_CB<3>
J 0
(-7640 3860);
DISPLAY 0.659574 (-7640 3860);
PAINT MONO (-7640 3860);
DISPLAY INVISIBLE (-7640 3860);
FORCEPROP 1 LASTPIN (-7650 3850) BN 3
J 2
(-7638 3858);
DISPLAY 0.489362 (-7638 3858);
PAINT GREEN (-7638 3858);
FORCEPROP 2 LAST CDS_LIB mstr_standard
J 0
(-7700 3850);
DISPLAY 0.723404 (-7700 3850);
PAINT MONO (-7700 3850);
DISPLAY INVISIBLE (-7700 3850);
FORCEPROP 1 LAST BODY_TYPE PLUMBING
J 2
(-7700 3900);
DISPLAY 0.872340 (-7700 3900);
PAINT GREEN (-7700 3900);
DISPLAY INVISIBLE (-7700 3900);
FORCEPROP 1 LAST HDL_TAP TRUE
J 2
(-8025 3725);
DISPLAY 0.872340 (-8025 3725);
DISPLAY INVISIBLE (-8025 3725);
FORCEPROP 1 LAST PATH I34
J 2
(-7698 3850);
DISPLAY 0.872340 (-7698 3850);
PAINT GREEN (-7698 3850);
DISPLAY INVISIBLE (-7698 3850);
FORCEADD TAP..1
R 2
(-7700 3900);
FORCEPROP 3 LASTPIN (-7650 3900) SIG_NAME M_I_CPU0_SA_CB<4>
J 0
(-7640 3910);
DISPLAY 0.659574 (-7640 3910);
PAINT MONO (-7640 3910);
DISPLAY INVISIBLE (-7640 3910);
FORCEPROP 1 LASTPIN (-7650 3900) BN 4
J 2
(-7638 3908);
DISPLAY 0.489362 (-7638 3908);
PAINT GREEN (-7638 3908);
FORCEPROP 2 LAST CDS_LIB mstr_standard
J 0
(-7700 3900);
DISPLAY 0.723404 (-7700 3900);
PAINT MONO (-7700 3900);
DISPLAY INVISIBLE (-7700 3900);
FORCEPROP 1 LAST BODY_TYPE PLUMBING
J 2
(-7700 3950);
DISPLAY 0.872340 (-7700 3950);
PAINT GREEN (-7700 3950);
DISPLAY INVISIBLE (-7700 3950);
FORCEPROP 1 LAST HDL_TAP TRUE
J 2
(-8025 3775);
DISPLAY 0.872340 (-8025 3775);
DISPLAY INVISIBLE (-8025 3775);
FORCEPROP 1 LAST PATH I35
J 2
(-7698 3900);
DISPLAY 0.872340 (-7698 3900);
PAINT GREEN (-7698 3900);
DISPLAY INVISIBLE (-7698 3900);
FORCEADD TAP..1
(-6000 2250);
FORCEPROP 3 LASTPIN (-6050 2250) SIG_NAME M_I_CPU0_SB_DQ<0>
J 0
(-6040 2260);
DISPLAY 0.659574 (-6040 2260);
PAINT MONO (-6040 2260);
DISPLAY INVISIBLE (-6040 2260);
FORCEPROP 1 LASTPIN (-6050 2250) BN 0
J 0
(-6062 2258);
DISPLAY 0.489362 (-6062 2258);
PAINT GREEN (-6062 2258);
FORCEPROP 2 LAST CDS_LIB mstr_standard
J 0
(-6000 2250);
DISPLAY 0.723404 (-6000 2250);
PAINT MONO (-6000 2250);
DISPLAY INVISIBLE (-6000 2250);
FORCEPROP 1 LAST BODY_TYPE PLUMBING
J 0
(-6000 2300);
DISPLAY 0.872340 (-6000 2300);
PAINT GREEN (-6000 2300);
DISPLAY INVISIBLE (-6000 2300);
FORCEPROP 1 LAST HDL_TAP TRUE
J 0
(-5675 2125);
DISPLAY 0.872340 (-5675 2125);
DISPLAY INVISIBLE (-5675 2125);
FORCEPROP 1 LAST PATH I36
J 0
(-6002 2250);
DISPLAY 0.872340 (-6002 2250);
PAINT GREEN (-6002 2250);
DISPLAY INVISIBLE (-6002 2250);
FORCEADD TAP..1
(-6000 2350);
FORCEPROP 3 LASTPIN (-6050 2350) SIG_NAME M_I_CPU0_SB_DQ<2>
J 0
(-6040 2360);
DISPLAY 0.659574 (-6040 2360);
PAINT MONO (-6040 2360);
DISPLAY INVISIBLE (-6040 2360);
FORCEPROP 1 LASTPIN (-6050 2350) BN 2
J 0
(-6062 2358);
DISPLAY 0.489362 (-6062 2358);
PAINT GREEN (-6062 2358);
FORCEPROP 2 LAST CDS_LIB mstr_standard
J 0
(-6000 2350);
DISPLAY 0.723404 (-6000 2350);
PAINT MONO (-6000 2350);
DISPLAY INVISIBLE (-6000 2350);
FORCEPROP 1 LAST BODY_TYPE PLUMBING
J 0
(-6000 2400);
DISPLAY 0.872340 (-6000 2400);
PAINT GREEN (-6000 2400);
DISPLAY INVISIBLE (-6000 2400);
FORCEPROP 1 LAST HDL_TAP TRUE
J 0
(-5675 2225);
DISPLAY 0.872340 (-5675 2225);
DISPLAY INVISIBLE (-5675 2225);
FORCEPROP 1 LAST PATH I37
J 0
(-6002 2350);
DISPLAY 0.872340 (-6002 2350);
PAINT GREEN (-6002 2350);
DISPLAY INVISIBLE (-6002 2350);
FORCEADD TAP..1
(-6000 2400);
FORCEPROP 3 LASTPIN (-6050 2400) SIG_NAME M_I_CPU0_SB_DQ<3>
J 0
(-6040 2410);
DISPLAY 0.659574 (-6040 2410);
PAINT MONO (-6040 2410);
DISPLAY INVISIBLE (-6040 2410);
FORCEPROP 1 LASTPIN (-6050 2400) BN 3
J 0
(-6062 2408);
DISPLAY 0.489362 (-6062 2408);
PAINT GREEN (-6062 2408);
FORCEPROP 2 LAST CDS_LIB mstr_standard
J 0
(-6000 2400);
DISPLAY 0.723404 (-6000 2400);
PAINT MONO (-6000 2400);
DISPLAY INVISIBLE (-6000 2400);
FORCEPROP 1 LAST BODY_TYPE PLUMBING
J 0
(-6000 2450);
DISPLAY 0.872340 (-6000 2450);
PAINT GREEN (-6000 2450);
DISPLAY INVISIBLE (-6000 2450);
FORCEPROP 1 LAST HDL_TAP TRUE
J 0
(-5675 2275);
DISPLAY 0.872340 (-5675 2275);
DISPLAY INVISIBLE (-5675 2275);
FORCEPROP 1 LAST PATH I38
J 0
(-6002 2400);
DISPLAY 0.872340 (-6002 2400);
PAINT GREEN (-6002 2400);
DISPLAY INVISIBLE (-6002 2400);
FORCEADD TAP..1
(-6000 2300);
FORCEPROP 3 LASTPIN (-6050 2300) SIG_NAME M_I_CPU0_SB_DQ<1>
J 0
(-6040 2310);
DISPLAY 0.659574 (-6040 2310);
PAINT MONO (-6040 2310);
DISPLAY INVISIBLE (-6040 2310);
FORCEPROP 1 LASTPIN (-6050 2300) BN 1
J 0
(-6062 2308);
DISPLAY 0.489362 (-6062 2308);
PAINT GREEN (-6062 2308);
FORCEPROP 2 LAST CDS_LIB mstr_standard
J 0
(-6000 2300);
DISPLAY 0.723404 (-6000 2300);
PAINT MONO (-6000 2300);
DISPLAY INVISIBLE (-6000 2300);
FORCEPROP 1 LAST BODY_TYPE PLUMBING
J 0
(-6000 2350);
DISPLAY 0.872340 (-6000 2350);
PAINT GREEN (-6000 2350);
DISPLAY INVISIBLE (-6000 2350);
FORCEPROP 1 LAST HDL_TAP TRUE
J 0
(-5675 2175);
DISPLAY 0.872340 (-5675 2175);
DISPLAY INVISIBLE (-5675 2175);
FORCEPROP 1 LAST PATH I39
J 0
(-6002 2300);
DISPLAY 0.872340 (-6002 2300);
PAINT GREEN (-6002 2300);
DISPLAY INVISIBLE (-6002 2300);
FORCEADD TAP..1
(-6000 2450);
FORCEPROP 3 LASTPIN (-6050 2450) SIG_NAME M_I_CPU0_SB_DQ<4>
J 0
(-6040 2460);
DISPLAY 0.659574 (-6040 2460);
PAINT MONO (-6040 2460);
DISPLAY INVISIBLE (-6040 2460);
FORCEPROP 1 LASTPIN (-6050 2450) BN 4
J 0
(-6062 2458);
DISPLAY 0.489362 (-6062 2458);
PAINT GREEN (-6062 2458);
FORCEPROP 2 LAST CDS_LIB mstr_standard
J 0
(-6000 2450);
DISPLAY 0.723404 (-6000 2450);
PAINT MONO (-6000 2450);
DISPLAY INVISIBLE (-6000 2450);
FORCEPROP 1 LAST BODY_TYPE PLUMBING
J 0
(-6000 2500);
DISPLAY 0.872340 (-6000 2500);
PAINT GREEN (-6000 2500);
DISPLAY INVISIBLE (-6000 2500);
FORCEPROP 1 LAST HDL_TAP TRUE
J 0
(-5675 2325);
DISPLAY 0.872340 (-5675 2325);
DISPLAY INVISIBLE (-5675 2325);
FORCEPROP 1 LAST PATH I40
J 0
(-6002 2450);
DISPLAY 0.872340 (-6002 2450);
PAINT GREEN (-6002 2450);
DISPLAY INVISIBLE (-6002 2450);
FORCEADD TAP..1
(-6000 2500);
FORCEPROP 3 LASTPIN (-6050 2500) SIG_NAME M_I_CPU0_SB_DQ<5>
J 0
(-6040 2510);
DISPLAY 0.659574 (-6040 2510);
PAINT MONO (-6040 2510);
DISPLAY INVISIBLE (-6040 2510);
FORCEPROP 1 LASTPIN (-6050 2500) BN 5
J 0
(-6062 2508);
DISPLAY 0.489362 (-6062 2508);
PAINT GREEN (-6062 2508);
FORCEPROP 2 LAST CDS_LIB mstr_standard
J 0
(-6000 2500);
DISPLAY 0.723404 (-6000 2500);
PAINT MONO (-6000 2500);
DISPLAY INVISIBLE (-6000 2500);
FORCEPROP 1 LAST BODY_TYPE PLUMBING
J 0
(-6000 2550);
DISPLAY 0.872340 (-6000 2550);
PAINT GREEN (-6000 2550);
DISPLAY INVISIBLE (-6000 2550);
FORCEPROP 1 LAST HDL_TAP TRUE
J 0
(-5675 2375);
DISPLAY 0.872340 (-5675 2375);
DISPLAY INVISIBLE (-5675 2375);
FORCEPROP 1 LAST PATH I41
J 0
(-6002 2500);
DISPLAY 0.872340 (-6002 2500);
PAINT GREEN (-6002 2500);
DISPLAY INVISIBLE (-6002 2500);
FORCEADD TAP..1
(-6000 2550);
FORCEPROP 3 LASTPIN (-6050 2550) SIG_NAME M_I_CPU0_SB_DQ<6>
J 0
(-6040 2560);
DISPLAY 0.659574 (-6040 2560);
PAINT MONO (-6040 2560);
DISPLAY INVISIBLE (-6040 2560);
FORCEPROP 1 LASTPIN (-6050 2550) BN 6
J 0
(-6062 2558);
DISPLAY 0.489362 (-6062 2558);
PAINT GREEN (-6062 2558);
FORCEPROP 2 LAST CDS_LIB mstr_standard
J 0
(-6000 2550);
DISPLAY 0.723404 (-6000 2550);
PAINT MONO (-6000 2550);
DISPLAY INVISIBLE (-6000 2550);
FORCEPROP 1 LAST BODY_TYPE PLUMBING
J 0
(-6000 2600);
DISPLAY 0.872340 (-6000 2600);
PAINT GREEN (-6000 2600);
DISPLAY INVISIBLE (-6000 2600);
FORCEPROP 1 LAST HDL_TAP TRUE
J 0
(-5675 2425);
DISPLAY 0.872340 (-5675 2425);
DISPLAY INVISIBLE (-5675 2425);
FORCEPROP 1 LAST PATH I42
J 0
(-6002 2550);
DISPLAY 0.872340 (-6002 2550);
PAINT GREEN (-6002 2550);
DISPLAY INVISIBLE (-6002 2550);
FORCEADD TAP..1
(-6000 2600);
FORCEPROP 3 LASTPIN (-6050 2600) SIG_NAME M_I_CPU0_SB_DQ<7>
J 0
(-6040 2610);
DISPLAY 0.659574 (-6040 2610);
PAINT MONO (-6040 2610);
DISPLAY INVISIBLE (-6040 2610);
FORCEPROP 1 LASTPIN (-6050 2600) BN 7
J 0
(-6062 2608);
DISPLAY 0.489362 (-6062 2608);
PAINT GREEN (-6062 2608);
FORCEPROP 2 LAST CDS_LIB mstr_standard
J 0
(-6000 2600);
DISPLAY 0.723404 (-6000 2600);
PAINT MONO (-6000 2600);
DISPLAY INVISIBLE (-6000 2600);
FORCEPROP 1 LAST BODY_TYPE PLUMBING
J 0
(-6000 2650);
DISPLAY 0.872340 (-6000 2650);
PAINT GREEN (-6000 2650);
DISPLAY INVISIBLE (-6000 2650);
FORCEPROP 1 LAST HDL_TAP TRUE
J 0
(-5675 2475);
DISPLAY 0.872340 (-5675 2475);
DISPLAY INVISIBLE (-5675 2475);
FORCEPROP 1 LAST PATH I43
J 0
(-6002 2600);
DISPLAY 0.872340 (-6002 2600);
PAINT GREEN (-6002 2600);
DISPLAY INVISIBLE (-6002 2600);
FORCEADD TAP..1
(-6000 2650);
FORCEPROP 3 LASTPIN (-6050 2650) SIG_NAME M_I_CPU0_SB_DQ<8>
J 0
(-6040 2660);
DISPLAY 0.659574 (-6040 2660);
PAINT MONO (-6040 2660);
DISPLAY INVISIBLE (-6040 2660);
FORCEPROP 1 LASTPIN (-6050 2650) BN 8
J 0
(-6062 2658);
DISPLAY 0.489362 (-6062 2658);
PAINT GREEN (-6062 2658);
FORCEPROP 2 LAST CDS_LIB mstr_standard
J 0
(-6000 2650);
DISPLAY 0.723404 (-6000 2650);
PAINT MONO (-6000 2650);
DISPLAY INVISIBLE (-6000 2650);
FORCEPROP 1 LAST BODY_TYPE PLUMBING
J 0
(-6000 2700);
DISPLAY 0.872340 (-6000 2700);
PAINT GREEN (-6000 2700);
DISPLAY INVISIBLE (-6000 2700);
FORCEPROP 1 LAST HDL_TAP TRUE
J 0
(-5675 2525);
DISPLAY 0.872340 (-5675 2525);
DISPLAY INVISIBLE (-5675 2525);
FORCEPROP 1 LAST PATH I44
J 0
(-6002 2650);
DISPLAY 0.872340 (-6002 2650);
PAINT GREEN (-6002 2650);
DISPLAY INVISIBLE (-6002 2650);
FORCEADD TAP..1
(-6000 2700);
FORCEPROP 3 LASTPIN (-6050 2700) SIG_NAME M_I_CPU0_SB_DQ<9>
J 0
(-6040 2710);
DISPLAY 0.659574 (-6040 2710);
PAINT MONO (-6040 2710);
DISPLAY INVISIBLE (-6040 2710);
FORCEPROP 1 LASTPIN (-6050 2700) BN 9
J 0
(-6062 2708);
DISPLAY 0.489362 (-6062 2708);
PAINT GREEN (-6062 2708);
FORCEPROP 2 LAST CDS_LIB mstr_standard
J 0
(-6000 2700);
DISPLAY 0.723404 (-6000 2700);
PAINT MONO (-6000 2700);
DISPLAY INVISIBLE (-6000 2700);
FORCEPROP 1 LAST BODY_TYPE PLUMBING
J 0
(-6000 2750);
DISPLAY 0.872340 (-6000 2750);
PAINT GREEN (-6000 2750);
DISPLAY INVISIBLE (-6000 2750);
FORCEPROP 1 LAST HDL_TAP TRUE
J 0
(-5675 2575);
DISPLAY 0.872340 (-5675 2575);
DISPLAY INVISIBLE (-5675 2575);
FORCEPROP 1 LAST PATH I45
J 0
(-6002 2700);
DISPLAY 0.872340 (-6002 2700);
PAINT GREEN (-6002 2700);
DISPLAY INVISIBLE (-6002 2700);
FORCEADD TAP..1
(-6000 2750);
FORCEPROP 3 LASTPIN (-6050 2750) SIG_NAME M_I_CPU0_SB_DQ<10>
J 0
(-6040 2760);
DISPLAY 0.659574 (-6040 2760);
PAINT MONO (-6040 2760);
DISPLAY INVISIBLE (-6040 2760);
FORCEPROP 1 LASTPIN (-6050 2750) BN 10
J 0
(-6062 2758);
DISPLAY 0.489362 (-6062 2758);
PAINT GREEN (-6062 2758);
FORCEPROP 2 LAST CDS_LIB mstr_standard
J 0
(-6000 2750);
DISPLAY 0.723404 (-6000 2750);
PAINT MONO (-6000 2750);
DISPLAY INVISIBLE (-6000 2750);
FORCEPROP 1 LAST BODY_TYPE PLUMBING
J 0
(-6000 2800);
DISPLAY 0.872340 (-6000 2800);
PAINT GREEN (-6000 2800);
DISPLAY INVISIBLE (-6000 2800);
FORCEPROP 1 LAST HDL_TAP TRUE
J 0
(-5675 2625);
DISPLAY 0.872340 (-5675 2625);
DISPLAY INVISIBLE (-5675 2625);
FORCEPROP 1 LAST PATH I46
J 0
(-6002 2750);
DISPLAY 0.872340 (-6002 2750);
PAINT GREEN (-6002 2750);
DISPLAY INVISIBLE (-6002 2750);
FORCEADD TAP..1
(-6000 2800);
FORCEPROP 3 LASTPIN (-6050 2800) SIG_NAME M_I_CPU0_SB_DQ<11>
J 0
(-6040 2810);
DISPLAY 0.659574 (-6040 2810);
PAINT MONO (-6040 2810);
DISPLAY INVISIBLE (-6040 2810);
FORCEPROP 1 LASTPIN (-6050 2800) BN 11
J 0
(-6062 2808);
DISPLAY 0.489362 (-6062 2808);
PAINT GREEN (-6062 2808);
FORCEPROP 2 LAST CDS_LIB mstr_standard
J 0
(-6000 2800);
DISPLAY 0.723404 (-6000 2800);
PAINT MONO (-6000 2800);
DISPLAY INVISIBLE (-6000 2800);
FORCEPROP 1 LAST BODY_TYPE PLUMBING
J 0
(-6000 2850);
DISPLAY 0.872340 (-6000 2850);
PAINT GREEN (-6000 2850);
DISPLAY INVISIBLE (-6000 2850);
FORCEPROP 1 LAST HDL_TAP TRUE
J 0
(-5675 2675);
DISPLAY 0.872340 (-5675 2675);
DISPLAY INVISIBLE (-5675 2675);
FORCEPROP 1 LAST PATH I47
J 0
(-6002 2800);
DISPLAY 0.872340 (-6002 2800);
PAINT GREEN (-6002 2800);
DISPLAY INVISIBLE (-6002 2800);
FORCEADD TAP..1
(-6000 2900);
FORCEPROP 3 LASTPIN (-6050 2900) SIG_NAME M_I_CPU0_SB_DQ<13>
J 0
(-6040 2910);
DISPLAY 0.659574 (-6040 2910);
PAINT MONO (-6040 2910);
DISPLAY INVISIBLE (-6040 2910);
FORCEPROP 1 LASTPIN (-6050 2900) BN 13
J 0
(-6062 2908);
DISPLAY 0.489362 (-6062 2908);
PAINT GREEN (-6062 2908);
FORCEPROP 2 LAST CDS_LIB mstr_standard
J 0
(-6000 2900);
DISPLAY 0.723404 (-6000 2900);
PAINT MONO (-6000 2900);
DISPLAY INVISIBLE (-6000 2900);
FORCEPROP 1 LAST BODY_TYPE PLUMBING
J 0
(-6000 2950);
DISPLAY 0.872340 (-6000 2950);
PAINT GREEN (-6000 2950);
DISPLAY INVISIBLE (-6000 2950);
FORCEPROP 1 LAST HDL_TAP TRUE
J 0
(-5675 2775);
DISPLAY 0.872340 (-5675 2775);
DISPLAY INVISIBLE (-5675 2775);
FORCEPROP 1 LAST PATH I48
J 0
(-6002 2900);
DISPLAY 0.872340 (-6002 2900);
PAINT GREEN (-6002 2900);
DISPLAY INVISIBLE (-6002 2900);
FORCEADD TAP..1
(-6000 2850);
FORCEPROP 3 LASTPIN (-6050 2850) SIG_NAME M_I_CPU0_SB_DQ<12>
J 0
(-6040 2860);
DISPLAY 0.659574 (-6040 2860);
PAINT MONO (-6040 2860);
DISPLAY INVISIBLE (-6040 2860);
FORCEPROP 1 LASTPIN (-6050 2850) BN 12
J 0
(-6062 2858);
DISPLAY 0.489362 (-6062 2858);
PAINT GREEN (-6062 2858);
FORCEPROP 2 LAST CDS_LIB mstr_standard
J 0
(-6000 2850);
DISPLAY 0.723404 (-6000 2850);
PAINT MONO (-6000 2850);
DISPLAY INVISIBLE (-6000 2850);
FORCEPROP 1 LAST BODY_TYPE PLUMBING
J 0
(-6000 2900);
DISPLAY 0.872340 (-6000 2900);
PAINT GREEN (-6000 2900);
DISPLAY INVISIBLE (-6000 2900);
FORCEPROP 1 LAST HDL_TAP TRUE
J 0
(-5675 2725);
DISPLAY 0.872340 (-5675 2725);
DISPLAY INVISIBLE (-5675 2725);
FORCEPROP 1 LAST PATH I49
J 0
(-6002 2850);
DISPLAY 0.872340 (-6002 2850);
PAINT GREEN (-6002 2850);
DISPLAY INVISIBLE (-6002 2850);
FORCEADD TAP..1
(-6000 2950);
FORCEPROP 3 LASTPIN (-6050 2950) SIG_NAME M_I_CPU0_SB_DQ<14>
J 0
(-6040 2960);
DISPLAY 0.659574 (-6040 2960);
PAINT MONO (-6040 2960);
DISPLAY INVISIBLE (-6040 2960);
FORCEPROP 1 LASTPIN (-6050 2950) BN 14
J 0
(-6062 2958);
DISPLAY 0.489362 (-6062 2958);
PAINT GREEN (-6062 2958);
FORCEPROP 2 LAST CDS_LIB mstr_standard
J 0
(-6000 2950);
DISPLAY 0.723404 (-6000 2950);
PAINT MONO (-6000 2950);
DISPLAY INVISIBLE (-6000 2950);
FORCEPROP 1 LAST BODY_TYPE PLUMBING
J 0
(-6000 3000);
DISPLAY 0.872340 (-6000 3000);
PAINT GREEN (-6000 3000);
DISPLAY INVISIBLE (-6000 3000);
FORCEPROP 1 LAST HDL_TAP TRUE
J 0
(-5675 2825);
DISPLAY 0.872340 (-5675 2825);
DISPLAY INVISIBLE (-5675 2825);
FORCEPROP 1 LAST PATH I50
J 0
(-6002 2950);
DISPLAY 0.872340 (-6002 2950);
PAINT GREEN (-6002 2950);
DISPLAY INVISIBLE (-6002 2950);
FORCEADD TAP..1
(-6000 3000);
FORCEPROP 3 LASTPIN (-6050 3000) SIG_NAME M_I_CPU0_SB_DQ<15>
J 0
(-6040 3010);
DISPLAY 0.659574 (-6040 3010);
PAINT MONO (-6040 3010);
DISPLAY INVISIBLE (-6040 3010);
FORCEPROP 1 LASTPIN (-6050 3000) BN 15
J 0
(-6062 3008);
DISPLAY 0.489362 (-6062 3008);
PAINT GREEN (-6062 3008);
FORCEPROP 2 LAST CDS_LIB mstr_standard
J 0
(-6000 3000);
DISPLAY 0.723404 (-6000 3000);
PAINT MONO (-6000 3000);
DISPLAY INVISIBLE (-6000 3000);
FORCEPROP 1 LAST BODY_TYPE PLUMBING
J 0
(-6000 3050);
DISPLAY 0.872340 (-6000 3050);
PAINT GREEN (-6000 3050);
DISPLAY INVISIBLE (-6000 3050);
FORCEPROP 1 LAST HDL_TAP TRUE
J 0
(-5675 2875);
DISPLAY 0.872340 (-5675 2875);
DISPLAY INVISIBLE (-5675 2875);
FORCEPROP 1 LAST PATH I51
J 0
(-6002 3000);
DISPLAY 0.872340 (-6002 3000);
PAINT GREEN (-6002 3000);
DISPLAY INVISIBLE (-6002 3000);
FORCEADD TAP..1
(-6000 3050);
FORCEPROP 3 LASTPIN (-6050 3050) SIG_NAME M_I_CPU0_SB_DQ<16>
J 0
(-6040 3060);
DISPLAY 0.659574 (-6040 3060);
PAINT MONO (-6040 3060);
DISPLAY INVISIBLE (-6040 3060);
FORCEPROP 1 LASTPIN (-6050 3050) BN 16
J 0
(-6062 3058);
DISPLAY 0.489362 (-6062 3058);
PAINT GREEN (-6062 3058);
FORCEPROP 2 LAST CDS_LIB mstr_standard
J 0
(-6000 3050);
DISPLAY 0.723404 (-6000 3050);
PAINT MONO (-6000 3050);
DISPLAY INVISIBLE (-6000 3050);
FORCEPROP 1 LAST BODY_TYPE PLUMBING
J 0
(-6000 3100);
DISPLAY 0.872340 (-6000 3100);
PAINT GREEN (-6000 3100);
DISPLAY INVISIBLE (-6000 3100);
FORCEPROP 1 LAST HDL_TAP TRUE
J 0
(-5675 2925);
DISPLAY 0.872340 (-5675 2925);
DISPLAY INVISIBLE (-5675 2925);
FORCEPROP 1 LAST PATH I52
J 0
(-6002 3050);
DISPLAY 0.872340 (-6002 3050);
PAINT GREEN (-6002 3050);
DISPLAY INVISIBLE (-6002 3050);
FORCEADD TAP..1
(-6000 3100);
FORCEPROP 3 LASTPIN (-6050 3100) SIG_NAME M_I_CPU0_SB_DQ<17>
J 0
(-6040 3110);
DISPLAY 0.659574 (-6040 3110);
PAINT MONO (-6040 3110);
DISPLAY INVISIBLE (-6040 3110);
FORCEPROP 1 LASTPIN (-6050 3100) BN 17
J 0
(-6062 3108);
DISPLAY 0.489362 (-6062 3108);
PAINT GREEN (-6062 3108);
FORCEPROP 2 LAST CDS_LIB mstr_standard
J 0
(-6000 3100);
DISPLAY 0.723404 (-6000 3100);
PAINT MONO (-6000 3100);
DISPLAY INVISIBLE (-6000 3100);
FORCEPROP 1 LAST BODY_TYPE PLUMBING
J 0
(-6000 3150);
DISPLAY 0.872340 (-6000 3150);
PAINT GREEN (-6000 3150);
DISPLAY INVISIBLE (-6000 3150);
FORCEPROP 1 LAST HDL_TAP TRUE
J 0
(-5675 2975);
DISPLAY 0.872340 (-5675 2975);
DISPLAY INVISIBLE (-5675 2975);
FORCEPROP 1 LAST PATH I53
J 0
(-6002 3100);
DISPLAY 0.872340 (-6002 3100);
PAINT GREEN (-6002 3100);
DISPLAY INVISIBLE (-6002 3100);
FORCEADD TAP..1
(-6000 3150);
FORCEPROP 3 LASTPIN (-6050 3150) SIG_NAME M_I_CPU0_SB_DQ<18>
J 0
(-6040 3160);
DISPLAY 0.659574 (-6040 3160);
PAINT MONO (-6040 3160);
DISPLAY INVISIBLE (-6040 3160);
FORCEPROP 1 LASTPIN (-6050 3150) BN 18
J 0
(-6062 3158);
DISPLAY 0.489362 (-6062 3158);
PAINT GREEN (-6062 3158);
FORCEPROP 2 LAST CDS_LIB mstr_standard
J 0
(-6000 3150);
DISPLAY 0.723404 (-6000 3150);
PAINT MONO (-6000 3150);
DISPLAY INVISIBLE (-6000 3150);
FORCEPROP 1 LAST BODY_TYPE PLUMBING
J 0
(-6000 3200);
DISPLAY 0.872340 (-6000 3200);
PAINT GREEN (-6000 3200);
DISPLAY INVISIBLE (-6000 3200);
FORCEPROP 1 LAST HDL_TAP TRUE
J 0
(-5675 3025);
DISPLAY 0.872340 (-5675 3025);
DISPLAY INVISIBLE (-5675 3025);
FORCEPROP 1 LAST PATH I54
J 0
(-6002 3150);
DISPLAY 0.872340 (-6002 3150);
PAINT GREEN (-6002 3150);
DISPLAY INVISIBLE (-6002 3150);
FORCEADD TAP..1
(-6000 3200);
FORCEPROP 3 LASTPIN (-6050 3200) SIG_NAME M_I_CPU0_SB_DQ<19>
J 0
(-6040 3210);
DISPLAY 0.659574 (-6040 3210);
PAINT MONO (-6040 3210);
DISPLAY INVISIBLE (-6040 3210);
FORCEPROP 1 LASTPIN (-6050 3200) BN 19
J 0
(-6062 3208);
DISPLAY 0.489362 (-6062 3208);
PAINT GREEN (-6062 3208);
FORCEPROP 2 LAST CDS_LIB mstr_standard
J 0
(-6000 3200);
DISPLAY 0.723404 (-6000 3200);
PAINT MONO (-6000 3200);
DISPLAY INVISIBLE (-6000 3200);
FORCEPROP 1 LAST BODY_TYPE PLUMBING
J 0
(-6000 3250);
DISPLAY 0.872340 (-6000 3250);
PAINT GREEN (-6000 3250);
DISPLAY INVISIBLE (-6000 3250);
FORCEPROP 1 LAST HDL_TAP TRUE
J 0
(-5675 3075);
DISPLAY 0.872340 (-5675 3075);
DISPLAY INVISIBLE (-5675 3075);
FORCEPROP 1 LAST PATH I55
J 0
(-6002 3200);
DISPLAY 0.872340 (-6002 3200);
PAINT GREEN (-6002 3200);
DISPLAY INVISIBLE (-6002 3200);
FORCEADD TAP..1
(-6000 3250);
FORCEPROP 3 LASTPIN (-6050 3250) SIG_NAME M_I_CPU0_SB_DQ<20>
J 0
(-6040 3260);
DISPLAY 0.659574 (-6040 3260);
PAINT MONO (-6040 3260);
DISPLAY INVISIBLE (-6040 3260);
FORCEPROP 1 LASTPIN (-6050 3250) BN 20
J 0
(-6062 3258);
DISPLAY 0.489362 (-6062 3258);
PAINT GREEN (-6062 3258);
FORCEPROP 2 LAST CDS_LIB mstr_standard
J 0
(-6000 3250);
DISPLAY 0.723404 (-6000 3250);
PAINT MONO (-6000 3250);
DISPLAY INVISIBLE (-6000 3250);
FORCEPROP 1 LAST BODY_TYPE PLUMBING
J 0
(-6000 3300);
DISPLAY 0.872340 (-6000 3300);
PAINT GREEN (-6000 3300);
DISPLAY INVISIBLE (-6000 3300);
FORCEPROP 1 LAST HDL_TAP TRUE
J 0
(-5675 3125);
DISPLAY 0.872340 (-5675 3125);
DISPLAY INVISIBLE (-5675 3125);
FORCEPROP 1 LAST PATH I56
J 0
(-6002 3250);
DISPLAY 0.872340 (-6002 3250);
PAINT GREEN (-6002 3250);
DISPLAY INVISIBLE (-6002 3250);
FORCEADD TAP..1
(-6000 3300);
FORCEPROP 3 LASTPIN (-6050 3300) SIG_NAME M_I_CPU0_SB_DQ<21>
J 0
(-6040 3310);
DISPLAY 0.659574 (-6040 3310);
PAINT MONO (-6040 3310);
DISPLAY INVISIBLE (-6040 3310);
FORCEPROP 1 LASTPIN (-6050 3300) BN 21
J 0
(-6062 3308);
DISPLAY 0.489362 (-6062 3308);
PAINT GREEN (-6062 3308);
FORCEPROP 2 LAST CDS_LIB mstr_standard
J 0
(-6000 3300);
DISPLAY 0.723404 (-6000 3300);
PAINT MONO (-6000 3300);
DISPLAY INVISIBLE (-6000 3300);
FORCEPROP 1 LAST BODY_TYPE PLUMBING
J 0
(-6000 3350);
DISPLAY 0.872340 (-6000 3350);
PAINT GREEN (-6000 3350);
DISPLAY INVISIBLE (-6000 3350);
FORCEPROP 1 LAST HDL_TAP TRUE
J 0
(-5675 3175);
DISPLAY 0.872340 (-5675 3175);
DISPLAY INVISIBLE (-5675 3175);
FORCEPROP 1 LAST PATH I57
J 0
(-6002 3300);
DISPLAY 0.872340 (-6002 3300);
PAINT GREEN (-6002 3300);
DISPLAY INVISIBLE (-6002 3300);
FORCEADD TAP..1
(-6000 3350);
FORCEPROP 3 LASTPIN (-6050 3350) SIG_NAME M_I_CPU0_SB_DQ<22>
J 0
(-6040 3360);
DISPLAY 0.659574 (-6040 3360);
PAINT MONO (-6040 3360);
DISPLAY INVISIBLE (-6040 3360);
FORCEPROP 1 LASTPIN (-6050 3350) BN 22
J 0
(-6062 3358);
DISPLAY 0.489362 (-6062 3358);
PAINT GREEN (-6062 3358);
FORCEPROP 2 LAST CDS_LIB mstr_standard
J 0
(-6000 3350);
DISPLAY 0.723404 (-6000 3350);
PAINT MONO (-6000 3350);
DISPLAY INVISIBLE (-6000 3350);
FORCEPROP 1 LAST BODY_TYPE PLUMBING
J 0
(-6000 3400);
DISPLAY 0.872340 (-6000 3400);
PAINT GREEN (-6000 3400);
DISPLAY INVISIBLE (-6000 3400);
FORCEPROP 1 LAST HDL_TAP TRUE
J 0
(-5675 3225);
DISPLAY 0.872340 (-5675 3225);
DISPLAY INVISIBLE (-5675 3225);
FORCEPROP 1 LAST PATH I58
J 0
(-6002 3350);
DISPLAY 0.872340 (-6002 3350);
PAINT GREEN (-6002 3350);
DISPLAY INVISIBLE (-6002 3350);
FORCEADD TAP..1
(-6000 3400);
FORCEPROP 3 LASTPIN (-6050 3400) SIG_NAME M_I_CPU0_SB_DQ<23>
J 0
(-6040 3410);
DISPLAY 0.659574 (-6040 3410);
PAINT MONO (-6040 3410);
DISPLAY INVISIBLE (-6040 3410);
FORCEPROP 1 LASTPIN (-6050 3400) BN 23
J 0
(-6062 3408);
DISPLAY 0.489362 (-6062 3408);
PAINT GREEN (-6062 3408);
FORCEPROP 2 LAST CDS_LIB mstr_standard
J 0
(-6000 3400);
DISPLAY 0.723404 (-6000 3400);
PAINT MONO (-6000 3400);
DISPLAY INVISIBLE (-6000 3400);
FORCEPROP 1 LAST BODY_TYPE PLUMBING
J 0
(-6000 3450);
DISPLAY 0.872340 (-6000 3450);
PAINT GREEN (-6000 3450);
DISPLAY INVISIBLE (-6000 3450);
FORCEPROP 1 LAST HDL_TAP TRUE
J 0
(-5675 3275);
DISPLAY 0.872340 (-5675 3275);
DISPLAY INVISIBLE (-5675 3275);
FORCEPROP 1 LAST PATH I59
J 0
(-6002 3400);
DISPLAY 0.872340 (-6002 3400);
PAINT GREEN (-6002 3400);
DISPLAY INVISIBLE (-6002 3400);
FORCEADD OFFPAGE..1
(-8300 2950);
FORCEPROP 2 LAST $XR0 93 
J 0
(-8521 2950);
DISPLAY 0.638298 (-8521 2950);
PAINT MONO (-8521 2950);
FORCEPROP 2 LAST PATH I6
J 0
(-8550 3000);
DISPLAY 1.021277 (-8550 3000);
DISPLAY INVISIBLE (-8550 3000);
FORCEPROP 1 LAST COMMENT_BODY TRUE
J 0
(-8175 2850);
DISPLAY 0.872340 (-8175 2850);
PAINT GREEN (-8175 2850);
DISPLAY INVISIBLE (-8175 2850);
FORCEPROP 1 LAST OFFPAGE TRUE
J 0
(-7975 2825);
DISPLAY 0.872340 (-7975 2825);
PAINT GREEN (-7975 2825);
DISPLAY INVISIBLE (-7975 2825);
FORCEPROP 2 LAST CDS_LIB mstr_standard
J 0
(-8300 2950);
DISPLAY 0.808511 (-8300 2950);
DISPLAY INVISIBLE (-8300 2950);
FORCEADD TAP..1
(-6000 3450);
FORCEPROP 3 LASTPIN (-6050 3450) SIG_NAME M_I_CPU0_SB_DQ<24>
J 0
(-6040 3460);
DISPLAY 0.659574 (-6040 3460);
PAINT MONO (-6040 3460);
DISPLAY INVISIBLE (-6040 3460);
FORCEPROP 1 LASTPIN (-6050 3450) BN 24
J 0
(-6062 3458);
DISPLAY 0.489362 (-6062 3458);
PAINT GREEN (-6062 3458);
FORCEPROP 2 LAST CDS_LIB mstr_standard
J 0
(-6000 3450);
DISPLAY 0.723404 (-6000 3450);
PAINT MONO (-6000 3450);
DISPLAY INVISIBLE (-6000 3450);
FORCEPROP 1 LAST BODY_TYPE PLUMBING
J 0
(-6000 3500);
DISPLAY 0.872340 (-6000 3500);
PAINT GREEN (-6000 3500);
DISPLAY INVISIBLE (-6000 3500);
FORCEPROP 1 LAST HDL_TAP TRUE
J 0
(-5675 3325);
DISPLAY 0.872340 (-5675 3325);
DISPLAY INVISIBLE (-5675 3325);
FORCEPROP 1 LAST PATH I60
J 0
(-6002 3450);
DISPLAY 0.872340 (-6002 3450);
PAINT GREEN (-6002 3450);
DISPLAY INVISIBLE (-6002 3450);
FORCEADD TAP..1
(-6000 3500);
FORCEPROP 3 LASTPIN (-6050 3500) SIG_NAME M_I_CPU0_SB_DQ<25>
J 0
(-6040 3510);
DISPLAY 0.659574 (-6040 3510);
PAINT MONO (-6040 3510);
DISPLAY INVISIBLE (-6040 3510);
FORCEPROP 1 LASTPIN (-6050 3500) BN 25
J 0
(-6062 3508);
DISPLAY 0.489362 (-6062 3508);
PAINT GREEN (-6062 3508);
FORCEPROP 2 LAST CDS_LIB mstr_standard
J 0
(-6000 3500);
DISPLAY 0.723404 (-6000 3500);
PAINT MONO (-6000 3500);
DISPLAY INVISIBLE (-6000 3500);
FORCEPROP 1 LAST BODY_TYPE PLUMBING
J 0
(-6000 3550);
DISPLAY 0.872340 (-6000 3550);
PAINT GREEN (-6000 3550);
DISPLAY INVISIBLE (-6000 3550);
FORCEPROP 1 LAST HDL_TAP TRUE
J 0
(-5675 3375);
DISPLAY 0.872340 (-5675 3375);
DISPLAY INVISIBLE (-5675 3375);
FORCEPROP 1 LAST PATH I61
J 0
(-6002 3500);
DISPLAY 0.872340 (-6002 3500);
PAINT GREEN (-6002 3500);
DISPLAY INVISIBLE (-6002 3500);
FORCEADD TAP..1
(-6000 3550);
FORCEPROP 3 LASTPIN (-6050 3550) SIG_NAME M_I_CPU0_SB_DQ<26>
J 0
(-6040 3560);
DISPLAY 0.659574 (-6040 3560);
PAINT MONO (-6040 3560);
DISPLAY INVISIBLE (-6040 3560);
FORCEPROP 1 LASTPIN (-6050 3550) BN 26
J 0
(-6062 3558);
DISPLAY 0.489362 (-6062 3558);
PAINT GREEN (-6062 3558);
FORCEPROP 2 LAST CDS_LIB mstr_standard
J 0
(-6000 3550);
DISPLAY 0.723404 (-6000 3550);
PAINT MONO (-6000 3550);
DISPLAY INVISIBLE (-6000 3550);
FORCEPROP 1 LAST BODY_TYPE PLUMBING
J 0
(-6000 3600);
DISPLAY 0.872340 (-6000 3600);
PAINT GREEN (-6000 3600);
DISPLAY INVISIBLE (-6000 3600);
FORCEPROP 1 LAST HDL_TAP TRUE
J 0
(-5675 3425);
DISPLAY 0.872340 (-5675 3425);
DISPLAY INVISIBLE (-5675 3425);
FORCEPROP 1 LAST PATH I62
J 0
(-6002 3550);
DISPLAY 0.872340 (-6002 3550);
PAINT GREEN (-6002 3550);
DISPLAY INVISIBLE (-6002 3550);
FORCEADD TAP..1
(-6000 3600);
FORCEPROP 3 LASTPIN (-6050 3600) SIG_NAME M_I_CPU0_SB_DQ<27>
J 0
(-6040 3610);
DISPLAY 0.659574 (-6040 3610);
PAINT MONO (-6040 3610);
DISPLAY INVISIBLE (-6040 3610);
FORCEPROP 1 LASTPIN (-6050 3600) BN 27
J 0
(-6062 3608);
DISPLAY 0.489362 (-6062 3608);
PAINT GREEN (-6062 3608);
FORCEPROP 2 LAST CDS_LIB mstr_standard
J 0
(-6000 3600);
DISPLAY 0.723404 (-6000 3600);
PAINT MONO (-6000 3600);
DISPLAY INVISIBLE (-6000 3600);
FORCEPROP 1 LAST BODY_TYPE PLUMBING
J 0
(-6000 3650);
DISPLAY 0.872340 (-6000 3650);
PAINT GREEN (-6000 3650);
DISPLAY INVISIBLE (-6000 3650);
FORCEPROP 1 LAST HDL_TAP TRUE
J 0
(-5675 3475);
DISPLAY 0.872340 (-5675 3475);
DISPLAY INVISIBLE (-5675 3475);
FORCEPROP 1 LAST PATH I63
J 0
(-6002 3600);
DISPLAY 0.872340 (-6002 3600);
PAINT GREEN (-6002 3600);
DISPLAY INVISIBLE (-6002 3600);
FORCEADD TAP..1
(-6000 3650);
FORCEPROP 3 LASTPIN (-6050 3650) SIG_NAME M_I_CPU0_SB_DQ<28>
J 0
(-6040 3660);
DISPLAY 0.659574 (-6040 3660);
PAINT MONO (-6040 3660);
DISPLAY INVISIBLE (-6040 3660);
FORCEPROP 1 LASTPIN (-6050 3650) BN 28
J 0
(-6062 3658);
DISPLAY 0.489362 (-6062 3658);
PAINT GREEN (-6062 3658);
FORCEPROP 2 LAST CDS_LIB mstr_standard
J 0
(-6000 3650);
DISPLAY 0.723404 (-6000 3650);
PAINT MONO (-6000 3650);
DISPLAY INVISIBLE (-6000 3650);
FORCEPROP 1 LAST BODY_TYPE PLUMBING
J 0
(-6000 3700);
DISPLAY 0.872340 (-6000 3700);
PAINT GREEN (-6000 3700);
DISPLAY INVISIBLE (-6000 3700);
FORCEPROP 1 LAST HDL_TAP TRUE
J 0
(-5675 3525);
DISPLAY 0.872340 (-5675 3525);
DISPLAY INVISIBLE (-5675 3525);
FORCEPROP 1 LAST PATH I64
J 0
(-6002 3650);
DISPLAY 0.872340 (-6002 3650);
PAINT GREEN (-6002 3650);
DISPLAY INVISIBLE (-6002 3650);
FORCEADD TAP..1
(-6000 3700);
FORCEPROP 3 LASTPIN (-6050 3700) SIG_NAME M_I_CPU0_SB_DQ<29>
J 0
(-6040 3710);
DISPLAY 0.659574 (-6040 3710);
PAINT MONO (-6040 3710);
DISPLAY INVISIBLE (-6040 3710);
FORCEPROP 1 LASTPIN (-6050 3700) BN 29
J 0
(-6062 3708);
DISPLAY 0.489362 (-6062 3708);
PAINT GREEN (-6062 3708);
FORCEPROP 2 LAST CDS_LIB mstr_standard
J 0
(-6000 3700);
DISPLAY 0.723404 (-6000 3700);
PAINT MONO (-6000 3700);
DISPLAY INVISIBLE (-6000 3700);
FORCEPROP 1 LAST BODY_TYPE PLUMBING
J 0
(-6000 3750);
DISPLAY 0.872340 (-6000 3750);
PAINT GREEN (-6000 3750);
DISPLAY INVISIBLE (-6000 3750);
FORCEPROP 1 LAST HDL_TAP TRUE
J 0
(-5675 3575);
DISPLAY 0.872340 (-5675 3575);
DISPLAY INVISIBLE (-5675 3575);
FORCEPROP 1 LAST PATH I65
J 0
(-6002 3700);
DISPLAY 0.872340 (-6002 3700);
PAINT GREEN (-6002 3700);
DISPLAY INVISIBLE (-6002 3700);
FORCEADD TAP..1
(-6000 3800);
FORCEPROP 3 LASTPIN (-6050 3800) SIG_NAME M_I_CPU0_SB_DQ<31>
J 0
(-6040 3810);
DISPLAY 0.659574 (-6040 3810);
PAINT MONO (-6040 3810);
DISPLAY INVISIBLE (-6040 3810);
FORCEPROP 1 LASTPIN (-6050 3800) BN 31
J 0
(-6062 3808);
DISPLAY 0.489362 (-6062 3808);
PAINT GREEN (-6062 3808);
FORCEPROP 2 LAST CDS_LIB mstr_standard
J 0
(-6000 3800);
DISPLAY 0.723404 (-6000 3800);
PAINT MONO (-6000 3800);
DISPLAY INVISIBLE (-6000 3800);
FORCEPROP 1 LAST BODY_TYPE PLUMBING
J 0
(-6000 3850);
DISPLAY 0.872340 (-6000 3850);
PAINT GREEN (-6000 3850);
DISPLAY INVISIBLE (-6000 3850);
FORCEPROP 1 LAST HDL_TAP TRUE
J 0
(-5675 3675);
DISPLAY 0.872340 (-5675 3675);
DISPLAY INVISIBLE (-5675 3675);
FORCEPROP 1 LAST PATH I66
J 0
(-6002 3800);
DISPLAY 0.872340 (-6002 3800);
PAINT GREEN (-6002 3800);
DISPLAY INVISIBLE (-6002 3800);
FORCEADD TAP..1
(-6000 3750);
FORCEPROP 3 LASTPIN (-6050 3750) SIG_NAME M_I_CPU0_SB_DQ<30>
J 0
(-6040 3760);
DISPLAY 0.659574 (-6040 3760);
PAINT MONO (-6040 3760);
DISPLAY INVISIBLE (-6040 3760);
FORCEPROP 1 LASTPIN (-6050 3750) BN 30
J 0
(-6062 3758);
DISPLAY 0.489362 (-6062 3758);
PAINT GREEN (-6062 3758);
FORCEPROP 2 LAST CDS_LIB mstr_standard
J 0
(-6000 3750);
DISPLAY 0.723404 (-6000 3750);
PAINT MONO (-6000 3750);
DISPLAY INVISIBLE (-6000 3750);
FORCEPROP 1 LAST BODY_TYPE PLUMBING
J 0
(-6000 3800);
DISPLAY 0.872340 (-6000 3800);
PAINT GREEN (-6000 3800);
DISPLAY INVISIBLE (-6000 3800);
FORCEPROP 1 LAST HDL_TAP TRUE
J 0
(-5675 3625);
DISPLAY 0.872340 (-5675 3625);
DISPLAY INVISIBLE (-5675 3625);
FORCEPROP 1 LAST PATH I67
J 0
(-6002 3750);
DISPLAY 0.872340 (-6002 3750);
PAINT GREEN (-6002 3750);
DISPLAY INVISIBLE (-6002 3750);
FORCEADD TAP..1
(-6000 3900);
FORCEPROP 3 LASTPIN (-6050 3900) SIG_NAME M_I_CPU0_SA_DQ<0>
J 0
(-6040 3910);
DISPLAY 0.659574 (-6040 3910);
PAINT MONO (-6040 3910);
DISPLAY INVISIBLE (-6040 3910);
FORCEPROP 1 LASTPIN (-6050 3900) BN 0
J 0
(-6062 3908);
DISPLAY 0.489362 (-6062 3908);
PAINT GREEN (-6062 3908);
FORCEPROP 2 LAST CDS_LIB mstr_standard
J 0
(-6000 3900);
DISPLAY 0.723404 (-6000 3900);
PAINT MONO (-6000 3900);
DISPLAY INVISIBLE (-6000 3900);
FORCEPROP 1 LAST BODY_TYPE PLUMBING
J 0
(-6000 3950);
DISPLAY 0.872340 (-6000 3950);
PAINT GREEN (-6000 3950);
DISPLAY INVISIBLE (-6000 3950);
FORCEPROP 1 LAST HDL_TAP TRUE
J 0
(-5675 3775);
DISPLAY 0.872340 (-5675 3775);
DISPLAY INVISIBLE (-5675 3775);
FORCEPROP 1 LAST PATH I68
J 0
(-6002 3900);
DISPLAY 0.872340 (-6002 3900);
PAINT GREEN (-6002 3900);
DISPLAY INVISIBLE (-6002 3900);
FORCEADD OFFPAGE..5
(-8125 3100);
FORCEPROP 2 LAST $XR0 18 
J 0
(-8349 3100);
DISPLAY 0.638298 (-8349 3100);
PAINT MONO (-8349 3100);
FORCEPROP 2 LAST PATH I7
J 0
(-8075 3175);
DISPLAY 1.021277 (-8075 3175);
DISPLAY INVISIBLE (-8075 3175);
FORCEPROP 1 LAST COMMENT_BODY TRUE
J 0
(-8025 3025);
DISPLAY 0.872340 (-8025 3025);
PAINT GREEN (-8025 3025);
DISPLAY INVISIBLE (-8025 3025);
FORCEPROP 1 LAST OFFPAGE TRUE
J 0
(-7800 2975);
DISPLAY 0.872340 (-7800 2975);
PAINT GREEN (-7800 2975);
DISPLAY INVISIBLE (-7800 2975);
FORCEPROP 2 LAST CDS_LIB mstr_standard
J 0
(-8125 3100);
DISPLAY INVISIBLE (-8125 3100);
FORCEADD OFFPAGE..3
(-5325 3825);
FORCEPROP 2 LAST $XR0 18 
J 0
(-5111 3825);
DISPLAY 0.638298 (-5111 3825);
PAINT MONO (-5111 3825);
FORCEPROP 2 LAST PATH I76
J 0
(-5125 3900);
DISPLAY 1.021277 (-5125 3900);
DISPLAY INVISIBLE (-5125 3900);
FORCEPROP 1 LAST COMMENT_BODY TRUE
J 0
(-5375 3725);
DISPLAY 0.872340 (-5375 3725);
PAINT GREEN (-5375 3725);
DISPLAY INVISIBLE (-5375 3725);
FORCEPROP 1 LAST OFFPAGE TRUE
J 0
(-5000 3700);
DISPLAY 0.872340 (-5000 3700);
PAINT GREEN (-5000 3700);
DISPLAY INVISIBLE (-5000 3700);
FORCEPROP 2 LAST CDS_LIB mstr_standard
J 0
(-5325 3825);
DISPLAY 0.723404 (-5325 3825);
PAINT MONO (-5325 3825);
DISPLAY INVISIBLE (-5325 3825);
FORCEADD TAP..1
R 2
(-7700 4050);
FORCEPROP 3 LASTPIN (-7650 4050) SIG_NAME M_I_CPU0_SA_CB<7>
J 0
(-7640 4060);
DISPLAY 0.659574 (-7640 4060);
PAINT MONO (-7640 4060);
DISPLAY INVISIBLE (-7640 4060);
FORCEPROP 1 LASTPIN (-7650 4050) BN 7
J 2
(-7638 4058);
DISPLAY 0.489362 (-7638 4058);
PAINT GREEN (-7638 4058);
FORCEPROP 2 LAST CDS_LIB mstr_standard
J 0
(-7700 4050);
DISPLAY 0.723404 (-7700 4050);
PAINT MONO (-7700 4050);
DISPLAY INVISIBLE (-7700 4050);
FORCEPROP 1 LAST BODY_TYPE PLUMBING
J 2
(-7700 4100);
DISPLAY 0.872340 (-7700 4100);
PAINT GREEN (-7700 4100);
DISPLAY INVISIBLE (-7700 4100);
FORCEPROP 1 LAST HDL_TAP TRUE
J 2
(-8025 3925);
DISPLAY 0.872340 (-8025 3925);
DISPLAY INVISIBLE (-8025 3925);
FORCEPROP 1 LAST PATH I77
J 2
(-7698 4050);
DISPLAY 0.872340 (-7698 4050);
PAINT GREEN (-7698 4050);
DISPLAY INVISIBLE (-7698 4050);
FORCEADD TAP..1
R 2
(-7700 4000);
FORCEPROP 3 LASTPIN (-7650 4000) SIG_NAME M_I_CPU0_SA_CB<6>
J 0
(-7640 4010);
DISPLAY 0.659574 (-7640 4010);
PAINT MONO (-7640 4010);
DISPLAY INVISIBLE (-7640 4010);
FORCEPROP 1 LASTPIN (-7650 4000) BN 6
J 2
(-7638 4008);
DISPLAY 0.489362 (-7638 4008);
PAINT GREEN (-7638 4008);
FORCEPROP 2 LAST CDS_LIB mstr_standard
J 0
(-7700 4000);
DISPLAY 0.723404 (-7700 4000);
PAINT MONO (-7700 4000);
DISPLAY INVISIBLE (-7700 4000);
FORCEPROP 1 LAST BODY_TYPE PLUMBING
J 2
(-7700 4050);
DISPLAY 0.872340 (-7700 4050);
PAINT GREEN (-7700 4050);
DISPLAY INVISIBLE (-7700 4050);
FORCEPROP 1 LAST HDL_TAP TRUE
J 2
(-8025 3875);
DISPLAY 0.872340 (-8025 3875);
DISPLAY INVISIBLE (-8025 3875);
FORCEPROP 1 LAST PATH I78
J 2
(-7698 4000);
DISPLAY 0.872340 (-7698 4000);
PAINT GREEN (-7698 4000);
DISPLAY INVISIBLE (-7698 4000);
FORCEADD TAP..1
R 2
(-7700 3950);
FORCEPROP 3 LASTPIN (-7650 3950) SIG_NAME M_I_CPU0_SA_CB<5>
J 0
(-7640 3960);
DISPLAY 0.659574 (-7640 3960);
PAINT MONO (-7640 3960);
DISPLAY INVISIBLE (-7640 3960);
FORCEPROP 1 LASTPIN (-7650 3950) BN 5
J 2
(-7638 3958);
DISPLAY 0.489362 (-7638 3958);
PAINT GREEN (-7638 3958);
FORCEPROP 2 LAST CDS_LIB mstr_standard
J 0
(-7700 3950);
DISPLAY 0.723404 (-7700 3950);
PAINT MONO (-7700 3950);
DISPLAY INVISIBLE (-7700 3950);
FORCEPROP 1 LAST BODY_TYPE PLUMBING
J 2
(-7700 4000);
DISPLAY 0.872340 (-7700 4000);
PAINT GREEN (-7700 4000);
DISPLAY INVISIBLE (-7700 4000);
FORCEPROP 1 LAST HDL_TAP TRUE
J 2
(-8025 3825);
DISPLAY 0.872340 (-8025 3825);
DISPLAY INVISIBLE (-8025 3825);
FORCEPROP 1 LAST PATH I79
J 2
(-7698 3950);
DISPLAY 0.872340 (-7698 3950);
PAINT GREEN (-7698 3950);
DISPLAY INVISIBLE (-7698 3950);
FORCEADD OFFPAGE..1
(-8125 3150);
FORCEPROP 2 LAST $XR0 18 
J 0
(-8376 3150);
DISPLAY 0.638298 (-8376 3150);
PAINT MONO (-8376 3150);
FORCEPROP 2 LAST PATH I8
J 0
(-8550 3200);
DISPLAY 1.021277 (-8550 3200);
DISPLAY INVISIBLE (-8550 3200);
FORCEPROP 1 LAST COMMENT_BODY TRUE
J 0
(-8000 3050);
DISPLAY 0.872340 (-8000 3050);
PAINT GREEN (-8000 3050);
DISPLAY INVISIBLE (-8000 3050);
FORCEPROP 1 LAST OFFPAGE TRUE
J 0
(-7800 3025);
DISPLAY 0.872340 (-7800 3025);
PAINT GREEN (-7800 3025);
DISPLAY INVISIBLE (-7800 3025);
FORCEPROP 2 LAST CDS_LIB mstr_standard
J 0
(-8125 3150);
DISPLAY 0.808511 (-8125 3150);
DISPLAY INVISIBLE (-8125 3150);
FORCEADD TAP..1
R 2
(-7700 4900);
FORCEPROP 3 LASTPIN (-7650 4900) SIG_NAME M_I_CPU0_SB_CA<3>
J 0
(-7640 4910);
DISPLAY 0.659574 (-7640 4910);
PAINT MONO (-7640 4910);
DISPLAY INVISIBLE (-7640 4910);
FORCEPROP 1 LASTPIN (-7650 4900) BN 3
J 2
(-7638 4908);
DISPLAY 0.489362 (-7638 4908);
PAINT GREEN (-7638 4908);
FORCEPROP 2 LAST CDS_LIB mstr_standard
J 0
(-7700 4900);
DISPLAY 0.723404 (-7700 4900);
PAINT MONO (-7700 4900);
DISPLAY INVISIBLE (-7700 4900);
FORCEPROP 1 LAST BODY_TYPE PLUMBING
J 2
(-7700 4950);
DISPLAY 0.872340 (-7700 4950);
PAINT GREEN (-7700 4950);
DISPLAY INVISIBLE (-7700 4950);
FORCEPROP 1 LAST HDL_TAP TRUE
J 2
(-8025 4775);
DISPLAY 0.872340 (-8025 4775);
DISPLAY INVISIBLE (-8025 4775);
FORCEPROP 1 LAST PATH I80
J 2
(-7698 4900);
DISPLAY 0.872340 (-7698 4900);
PAINT GREEN (-7698 4900);
DISPLAY INVISIBLE (-7698 4900);
FORCEADD TAP..1
R 2
(-7700 4850);
FORCEPROP 3 LASTPIN (-7650 4850) SIG_NAME M_I_CPU0_SB_CA<2>
J 0
(-7640 4860);
DISPLAY 0.659574 (-7640 4860);
PAINT MONO (-7640 4860);
DISPLAY INVISIBLE (-7640 4860);
FORCEPROP 1 LASTPIN (-7650 4850) BN 2
J 2
(-7638 4858);
DISPLAY 0.489362 (-7638 4858);
PAINT GREEN (-7638 4858);
FORCEPROP 2 LAST CDS_LIB mstr_standard
J 0
(-7700 4850);
DISPLAY 0.723404 (-7700 4850);
PAINT MONO (-7700 4850);
DISPLAY INVISIBLE (-7700 4850);
FORCEPROP 1 LAST BODY_TYPE PLUMBING
J 2
(-7700 4900);
DISPLAY 0.872340 (-7700 4900);
PAINT GREEN (-7700 4900);
DISPLAY INVISIBLE (-7700 4900);
FORCEPROP 1 LAST HDL_TAP TRUE
J 2
(-8025 4725);
DISPLAY 0.872340 (-8025 4725);
DISPLAY INVISIBLE (-8025 4725);
FORCEPROP 1 LAST PATH I81
J 2
(-7698 4850);
DISPLAY 0.872340 (-7698 4850);
PAINT GREEN (-7698 4850);
DISPLAY INVISIBLE (-7698 4850);
FORCEADD TAP..1
R 2
(-7700 4800);
FORCEPROP 3 LASTPIN (-7650 4800) SIG_NAME M_I_CPU0_SB_CA<1>
J 0
(-7640 4810);
DISPLAY 0.659574 (-7640 4810);
PAINT MONO (-7640 4810);
DISPLAY INVISIBLE (-7640 4810);
FORCEPROP 1 LASTPIN (-7650 4800) BN 1
J 2
(-7638 4808);
DISPLAY 0.489362 (-7638 4808);
PAINT GREEN (-7638 4808);
FORCEPROP 2 LAST CDS_LIB mstr_standard
J 0
(-7700 4800);
DISPLAY 0.723404 (-7700 4800);
PAINT MONO (-7700 4800);
DISPLAY INVISIBLE (-7700 4800);
FORCEPROP 1 LAST BODY_TYPE PLUMBING
J 2
(-7700 4850);
DISPLAY 0.872340 (-7700 4850);
PAINT GREEN (-7700 4850);
DISPLAY INVISIBLE (-7700 4850);
FORCEPROP 1 LAST HDL_TAP TRUE
J 2
(-8025 4675);
DISPLAY 0.872340 (-8025 4675);
DISPLAY INVISIBLE (-8025 4675);
FORCEPROP 1 LAST PATH I82
J 2
(-7698 4800);
DISPLAY 0.872340 (-7698 4800);
PAINT GREEN (-7698 4800);
DISPLAY INVISIBLE (-7698 4800);
FORCEADD TAP..1
R 2
(-7700 4750);
FORCEPROP 3 LASTPIN (-7650 4750) SIG_NAME M_I_CPU0_SB_CA<0>
J 0
(-7640 4760);
DISPLAY 0.659574 (-7640 4760);
PAINT MONO (-7640 4760);
DISPLAY INVISIBLE (-7640 4760);
FORCEPROP 1 LASTPIN (-7650 4750) BN 0
J 2
(-7638 4758);
DISPLAY 0.489362 (-7638 4758);
PAINT GREEN (-7638 4758);
FORCEPROP 2 LAST CDS_LIB mstr_standard
J 0
(-7700 4750);
DISPLAY 0.723404 (-7700 4750);
PAINT MONO (-7700 4750);
DISPLAY INVISIBLE (-7700 4750);
FORCEPROP 1 LAST BODY_TYPE PLUMBING
J 2
(-7700 4800);
DISPLAY 0.872340 (-7700 4800);
PAINT GREEN (-7700 4800);
DISPLAY INVISIBLE (-7700 4800);
FORCEPROP 1 LAST HDL_TAP TRUE
J 2
(-8025 4625);
DISPLAY 0.872340 (-8025 4625);
DISPLAY INVISIBLE (-8025 4625);
FORCEPROP 1 LAST PATH I83
J 2
(-7698 4750);
DISPLAY 0.872340 (-7698 4750);
PAINT GREEN (-7698 4750);
DISPLAY INVISIBLE (-7698 4750);
FORCEADD TAP..1
R 2
(-7700 4950);
FORCEPROP 3 LASTPIN (-7650 4950) SIG_NAME M_I_CPU0_SB_CA<4>
J 0
(-7640 4960);
DISPLAY 0.659574 (-7640 4960);
PAINT MONO (-7640 4960);
DISPLAY INVISIBLE (-7640 4960);
FORCEPROP 1 LASTPIN (-7650 4950) BN 4
J 2
(-7638 4958);
DISPLAY 0.489362 (-7638 4958);
PAINT GREEN (-7638 4958);
FORCEPROP 2 LAST CDS_LIB mstr_standard
J 0
(-7700 4950);
DISPLAY 0.723404 (-7700 4950);
PAINT MONO (-7700 4950);
DISPLAY INVISIBLE (-7700 4950);
FORCEPROP 1 LAST BODY_TYPE PLUMBING
J 2
(-7700 5000);
DISPLAY 0.872340 (-7700 5000);
PAINT GREEN (-7700 5000);
DISPLAY INVISIBLE (-7700 5000);
FORCEPROP 1 LAST HDL_TAP TRUE
J 2
(-8025 4825);
DISPLAY 0.872340 (-8025 4825);
DISPLAY INVISIBLE (-8025 4825);
FORCEPROP 1 LAST PATH I84
J 2
(-7698 4950);
DISPLAY 0.872340 (-7698 4950);
PAINT GREEN (-7698 4950);
DISPLAY INVISIBLE (-7698 4950);
FORCEADD TAP..1
R 2
(-7700 5000);
FORCEPROP 3 LASTPIN (-7650 5000) SIG_NAME M_I_CPU0_SB_CA<5>
J 0
(-7640 5010);
DISPLAY 0.659574 (-7640 5010);
PAINT MONO (-7640 5010);
DISPLAY INVISIBLE (-7640 5010);
FORCEPROP 1 LASTPIN (-7650 5000) BN 5
J 2
(-7638 5008);
DISPLAY 0.489362 (-7638 5008);
PAINT GREEN (-7638 5008);
FORCEPROP 2 LAST CDS_LIB mstr_standard
J 0
(-7700 5000);
DISPLAY 0.723404 (-7700 5000);
PAINT MONO (-7700 5000);
DISPLAY INVISIBLE (-7700 5000);
FORCEPROP 1 LAST BODY_TYPE PLUMBING
J 2
(-7700 5050);
DISPLAY 0.872340 (-7700 5050);
PAINT GREEN (-7700 5050);
DISPLAY INVISIBLE (-7700 5050);
FORCEPROP 1 LAST HDL_TAP TRUE
J 2
(-8025 4875);
DISPLAY 0.872340 (-8025 4875);
DISPLAY INVISIBLE (-8025 4875);
FORCEPROP 1 LAST PATH I85
J 2
(-7698 5000);
DISPLAY 0.872340 (-7698 5000);
PAINT GREEN (-7698 5000);
DISPLAY INVISIBLE (-7698 5000);
FORCEADD TAP..1
R 2
(-7700 5050);
FORCEPROP 3 LASTPIN (-7650 5050) SIG_NAME M_I_CPU0_SB_CA<6>
J 0
(-7640 5060);
DISPLAY 0.659574 (-7640 5060);
PAINT MONO (-7640 5060);
DISPLAY INVISIBLE (-7640 5060);
FORCEPROP 1 LASTPIN (-7650 5050) BN 6
J 2
(-7638 5058);
DISPLAY 0.489362 (-7638 5058);
PAINT GREEN (-7638 5058);
FORCEPROP 2 LAST CDS_LIB mstr_standard
J 0
(-7700 5050);
DISPLAY 0.723404 (-7700 5050);
PAINT MONO (-7700 5050);
DISPLAY INVISIBLE (-7700 5050);
FORCEPROP 1 LAST BODY_TYPE PLUMBING
J 2
(-7700 5100);
DISPLAY 0.872340 (-7700 5100);
PAINT GREEN (-7700 5100);
DISPLAY INVISIBLE (-7700 5100);
FORCEPROP 1 LAST HDL_TAP TRUE
J 2
(-8025 4925);
DISPLAY 0.872340 (-8025 4925);
DISPLAY INVISIBLE (-8025 4925);
FORCEPROP 1 LAST PATH I86
J 2
(-7698 5050);
DISPLAY 0.872340 (-7698 5050);
PAINT GREEN (-7698 5050);
DISPLAY INVISIBLE (-7698 5050);
FORCEADD TAP..1
R 2
(-7700 5200);
FORCEPROP 3 LASTPIN (-7650 5200) SIG_NAME M_I_CPU0_SA_CA<1>
J 0
(-7640 5210);
DISPLAY 0.659574 (-7640 5210);
PAINT MONO (-7640 5210);
DISPLAY INVISIBLE (-7640 5210);
FORCEPROP 1 LASTPIN (-7650 5200) BN 1
J 2
(-7638 5208);
DISPLAY 0.489362 (-7638 5208);
PAINT GREEN (-7638 5208);
FORCEPROP 2 LAST CDS_LIB mstr_standard
J 0
(-7700 5200);
DISPLAY 0.723404 (-7700 5200);
PAINT MONO (-7700 5200);
DISPLAY INVISIBLE (-7700 5200);
FORCEPROP 1 LAST BODY_TYPE PLUMBING
J 2
(-7700 5250);
DISPLAY 0.872340 (-7700 5250);
PAINT GREEN (-7700 5250);
DISPLAY INVISIBLE (-7700 5250);
FORCEPROP 1 LAST HDL_TAP TRUE
J 2
(-8025 5075);
DISPLAY 0.872340 (-8025 5075);
DISPLAY INVISIBLE (-8025 5075);
FORCEPROP 1 LAST PATH I87
J 2
(-7698 5200);
DISPLAY 0.872340 (-7698 5200);
PAINT GREEN (-7698 5200);
DISPLAY INVISIBLE (-7698 5200);
FORCEADD TAP..1
R 2
(-7700 5150);
FORCEPROP 3 LASTPIN (-7650 5150) SIG_NAME M_I_CPU0_SA_CA<0>
J 0
(-7640 5160);
DISPLAY 0.659574 (-7640 5160);
PAINT MONO (-7640 5160);
DISPLAY INVISIBLE (-7640 5160);
FORCEPROP 1 LASTPIN (-7650 5150) BN 0
J 2
(-7638 5158);
DISPLAY 0.489362 (-7638 5158);
PAINT GREEN (-7638 5158);
FORCEPROP 2 LAST CDS_LIB mstr_standard
J 0
(-7700 5150);
DISPLAY 0.723404 (-7700 5150);
PAINT MONO (-7700 5150);
DISPLAY INVISIBLE (-7700 5150);
FORCEPROP 1 LAST BODY_TYPE PLUMBING
J 2
(-7700 5200);
DISPLAY 0.872340 (-7700 5200);
PAINT GREEN (-7700 5200);
DISPLAY INVISIBLE (-7700 5200);
FORCEPROP 1 LAST HDL_TAP TRUE
J 2
(-8025 5025);
DISPLAY 0.872340 (-8025 5025);
DISPLAY INVISIBLE (-8025 5025);
FORCEPROP 1 LAST PATH I88
J 2
(-7698 5150);
DISPLAY 0.872340 (-7698 5150);
PAINT GREEN (-7698 5150);
DISPLAY INVISIBLE (-7698 5150);
FORCEADD TAP..1
R 2
(-7700 5250);
FORCEPROP 3 LASTPIN (-7650 5250) SIG_NAME M_I_CPU0_SA_CA<2>
J 0
(-7640 5260);
DISPLAY 0.659574 (-7640 5260);
PAINT MONO (-7640 5260);
DISPLAY INVISIBLE (-7640 5260);
FORCEPROP 1 LASTPIN (-7650 5250) BN 2
J 2
(-7638 5258);
DISPLAY 0.489362 (-7638 5258);
PAINT GREEN (-7638 5258);
FORCEPROP 2 LAST CDS_LIB mstr_standard
J 0
(-7700 5250);
DISPLAY 0.723404 (-7700 5250);
PAINT MONO (-7700 5250);
DISPLAY INVISIBLE (-7700 5250);
FORCEPROP 1 LAST BODY_TYPE PLUMBING
J 2
(-7700 5300);
DISPLAY 0.872340 (-7700 5300);
PAINT GREEN (-7700 5300);
DISPLAY INVISIBLE (-7700 5300);
FORCEPROP 1 LAST HDL_TAP TRUE
J 2
(-8025 5125);
DISPLAY 0.872340 (-8025 5125);
DISPLAY INVISIBLE (-8025 5125);
FORCEPROP 1 LAST PATH I89
J 2
(-7698 5250);
DISPLAY 0.872340 (-7698 5250);
PAINT GREEN (-7698 5250);
DISPLAY INVISIBLE (-7698 5250);
FORCEADD VCC_CORE..1
(-8550 3475);
FORCEPROP 3 LASTPIN (-8550 3425) SIG_NAME P3V3_STBY\g
J 0
(-8540 3435);
DISPLAY 0.659574 (-8540 3435);
PAINT MONO (-8540 3435);
DISPLAY INVISIBLE (-8540 3435);
FORCEPROP 1 LAST HDL_POWER P3V3_STBY
J 1
(-8550 3525);
DISPLAY 0.489362 (-8550 3525);
PAINT GREEN (-8550 3525);
FORCEPROP 2 LAST CDS_LIB mstr_symbols
J 0
(-8550 3475);
PAINT MONO (-8550 3475);
DISPLAY INVISIBLE (-8550 3475);
FORCEPROP 1 LAST PATH I9
J 0
(-8500 3500);
DISPLAY 0.872340 (-8500 3500);
PAINT AQUA (-8500 3500);
DISPLAY INVISIBLE (-8500 3500);
FORCEPROP 0 LAST VOLTAGE 3.3
J 0
(-8825 3625);
DISPLAY 1.021277 (-8825 3625);
PAINT SKYBLUE (-8825 3625);
DISPLAY INVISIBLE (-8825 3625);
FORCEPROP 2 LAST ROOM PVCCINFAON_CPU0_CTRL
J 0
(-8550 3575);
DISPLAY 0.808511 (-8550 3575);
PAINT RED (-8550 3575);
DISPLAY INVISIBLE (-8550 3575);
FORCEADD TAP..1
R 2
(-7700 5300);
FORCEPROP 3 LASTPIN (-7650 5300) SIG_NAME M_I_CPU0_SA_CA<3>
J 0
(-7640 5310);
DISPLAY 0.659574 (-7640 5310);
PAINT MONO (-7640 5310);
DISPLAY INVISIBLE (-7640 5310);
FORCEPROP 1 LASTPIN (-7650 5300) BN 3
J 2
(-7638 5308);
DISPLAY 0.489362 (-7638 5308);
PAINT GREEN (-7638 5308);
FORCEPROP 2 LAST CDS_LIB mstr_standard
J 0
(-7700 5300);
DISPLAY 0.723404 (-7700 5300);
PAINT MONO (-7700 5300);
DISPLAY INVISIBLE (-7700 5300);
FORCEPROP 1 LAST BODY_TYPE PLUMBING
J 2
(-7700 5350);
DISPLAY 0.872340 (-7700 5350);
PAINT GREEN (-7700 5350);
DISPLAY INVISIBLE (-7700 5350);
FORCEPROP 1 LAST HDL_TAP TRUE
J 2
(-8025 5175);
DISPLAY 0.872340 (-8025 5175);
DISPLAY INVISIBLE (-8025 5175);
FORCEPROP 1 LAST PATH I90
J 2
(-7698 5300);
DISPLAY 0.872340 (-7698 5300);
PAINT GREEN (-7698 5300);
DISPLAY INVISIBLE (-7698 5300);
FORCEADD TAP..1
R 2
(-7700 5350);
FORCEPROP 3 LASTPIN (-7650 5350) SIG_NAME M_I_CPU0_SA_CA<4>
J 0
(-7640 5360);
DISPLAY 0.659574 (-7640 5360);
PAINT MONO (-7640 5360);
DISPLAY INVISIBLE (-7640 5360);
FORCEPROP 1 LASTPIN (-7650 5350) BN 4
J 2
(-7638 5358);
DISPLAY 0.489362 (-7638 5358);
PAINT GREEN (-7638 5358);
FORCEPROP 2 LAST CDS_LIB mstr_standard
J 0
(-7700 5350);
DISPLAY 0.723404 (-7700 5350);
PAINT MONO (-7700 5350);
DISPLAY INVISIBLE (-7700 5350);
FORCEPROP 1 LAST BODY_TYPE PLUMBING
J 2
(-7700 5400);
DISPLAY 0.872340 (-7700 5400);
PAINT GREEN (-7700 5400);
DISPLAY INVISIBLE (-7700 5400);
FORCEPROP 1 LAST HDL_TAP TRUE
J 2
(-8025 5225);
DISPLAY 0.872340 (-8025 5225);
DISPLAY INVISIBLE (-8025 5225);
FORCEPROP 1 LAST PATH I91
J 2
(-7698 5350);
DISPLAY 0.872340 (-7698 5350);
PAINT GREEN (-7698 5350);
DISPLAY INVISIBLE (-7698 5350);
FORCEADD TAP..1
R 2
(-7700 5450);
FORCEPROP 3 LASTPIN (-7650 5450) SIG_NAME M_I_CPU0_SA_CA<6>
J 0
(-7640 5460);
DISPLAY 0.659574 (-7640 5460);
PAINT MONO (-7640 5460);
DISPLAY INVISIBLE (-7640 5460);
FORCEPROP 1 LASTPIN (-7650 5450) BN 6
J 2
(-7638 5458);
DISPLAY 0.489362 (-7638 5458);
PAINT GREEN (-7638 5458);
FORCEPROP 2 LAST CDS_LIB mstr_standard
J 0
(-7700 5450);
DISPLAY 0.723404 (-7700 5450);
PAINT MONO (-7700 5450);
DISPLAY INVISIBLE (-7700 5450);
FORCEPROP 1 LAST BODY_TYPE PLUMBING
J 2
(-7700 5500);
DISPLAY 0.872340 (-7700 5500);
PAINT GREEN (-7700 5500);
DISPLAY INVISIBLE (-7700 5500);
FORCEPROP 1 LAST HDL_TAP TRUE
J 2
(-8025 5325);
DISPLAY 0.872340 (-8025 5325);
DISPLAY INVISIBLE (-8025 5325);
FORCEPROP 1 LAST PATH I92
J 2
(-7698 5450);
DISPLAY 0.872340 (-7698 5450);
PAINT GREEN (-7698 5450);
DISPLAY INVISIBLE (-7698 5450);
FORCEADD TAP..1
R 2
(-7700 5400);
FORCEPROP 3 LASTPIN (-7650 5400) SIG_NAME M_I_CPU0_SA_CA<5>
J 0
(-7640 5410);
DISPLAY 0.659574 (-7640 5410);
PAINT MONO (-7640 5410);
DISPLAY INVISIBLE (-7640 5410);
FORCEPROP 1 LASTPIN (-7650 5400) BN 5
J 2
(-7638 5408);
DISPLAY 0.489362 (-7638 5408);
PAINT GREEN (-7638 5408);
FORCEPROP 2 LAST CDS_LIB mstr_standard
J 0
(-7700 5400);
DISPLAY 0.723404 (-7700 5400);
PAINT MONO (-7700 5400);
DISPLAY INVISIBLE (-7700 5400);
FORCEPROP 1 LAST BODY_TYPE PLUMBING
J 2
(-7700 5450);
DISPLAY 0.872340 (-7700 5450);
PAINT GREEN (-7700 5450);
DISPLAY INVISIBLE (-7700 5450);
FORCEPROP 1 LAST HDL_TAP TRUE
J 2
(-8025 5275);
DISPLAY 0.872340 (-8025 5275);
DISPLAY INVISIBLE (-8025 5275);
FORCEPROP 1 LAST PATH I93
J 2
(-7698 5400);
DISPLAY 0.872340 (-7698 5400);
PAINT GREEN (-7698 5400);
DISPLAY INVISIBLE (-7698 5400);
FORCEADD TAP..1
(-6000 3950);
FORCEPROP 3 LASTPIN (-6050 3950) SIG_NAME M_I_CPU0_SA_DQ<1>
J 0
(-6040 3960);
DISPLAY 0.659574 (-6040 3960);
PAINT MONO (-6040 3960);
DISPLAY INVISIBLE (-6040 3960);
FORCEPROP 1 LASTPIN (-6050 3950) BN 1
J 0
(-6062 3958);
DISPLAY 0.489362 (-6062 3958);
PAINT GREEN (-6062 3958);
FORCEPROP 2 LAST CDS_LIB mstr_standard
J 0
(-6000 3950);
DISPLAY 0.723404 (-6000 3950);
PAINT MONO (-6000 3950);
DISPLAY INVISIBLE (-6000 3950);
FORCEPROP 1 LAST BODY_TYPE PLUMBING
J 0
(-6000 4000);
DISPLAY 0.872340 (-6000 4000);
PAINT GREEN (-6000 4000);
DISPLAY INVISIBLE (-6000 4000);
FORCEPROP 1 LAST HDL_TAP TRUE
J 0
(-5675 3825);
DISPLAY 0.872340 (-5675 3825);
DISPLAY INVISIBLE (-5675 3825);
FORCEPROP 1 LAST PATH I94
J 0
(-6002 3950);
DISPLAY 0.872340 (-6002 3950);
PAINT GREEN (-6002 3950);
DISPLAY INVISIBLE (-6002 3950);
FORCEADD TAP..1
(-6000 4000);
FORCEPROP 3 LASTPIN (-6050 4000) SIG_NAME M_I_CPU0_SA_DQ<2>
J 0
(-6040 4010);
DISPLAY 0.659574 (-6040 4010);
PAINT MONO (-6040 4010);
DISPLAY INVISIBLE (-6040 4010);
FORCEPROP 1 LASTPIN (-6050 4000) BN 2
J 0
(-6062 4008);
DISPLAY 0.489362 (-6062 4008);
PAINT GREEN (-6062 4008);
FORCEPROP 2 LAST CDS_LIB mstr_standard
J 0
(-6000 4000);
DISPLAY 0.723404 (-6000 4000);
PAINT MONO (-6000 4000);
DISPLAY INVISIBLE (-6000 4000);
FORCEPROP 1 LAST BODY_TYPE PLUMBING
J 0
(-6000 4050);
DISPLAY 0.872340 (-6000 4050);
PAINT GREEN (-6000 4050);
DISPLAY INVISIBLE (-6000 4050);
FORCEPROP 1 LAST HDL_TAP TRUE
J 0
(-5675 3875);
DISPLAY 0.872340 (-5675 3875);
DISPLAY INVISIBLE (-5675 3875);
FORCEPROP 1 LAST PATH I95
J 0
(-6002 4000);
DISPLAY 0.872340 (-6002 4000);
PAINT GREEN (-6002 4000);
DISPLAY INVISIBLE (-6002 4000);
FORCEADD TAP..1
(-6000 4050);
FORCEPROP 3 LASTPIN (-6050 4050) SIG_NAME M_I_CPU0_SA_DQ<3>
J 0
(-6040 4060);
DISPLAY 0.659574 (-6040 4060);
PAINT MONO (-6040 4060);
DISPLAY INVISIBLE (-6040 4060);
FORCEPROP 1 LASTPIN (-6050 4050) BN 3
J 0
(-6062 4058);
DISPLAY 0.489362 (-6062 4058);
PAINT GREEN (-6062 4058);
FORCEPROP 2 LAST CDS_LIB mstr_standard
J 0
(-6000 4050);
DISPLAY 0.723404 (-6000 4050);
PAINT MONO (-6000 4050);
DISPLAY INVISIBLE (-6000 4050);
FORCEPROP 1 LAST BODY_TYPE PLUMBING
J 0
(-6000 4100);
DISPLAY 0.872340 (-6000 4100);
PAINT GREEN (-6000 4100);
DISPLAY INVISIBLE (-6000 4100);
FORCEPROP 1 LAST HDL_TAP TRUE
J 0
(-5675 3925);
DISPLAY 0.872340 (-5675 3925);
DISPLAY INVISIBLE (-5675 3925);
FORCEPROP 1 LAST PATH I96
J 0
(-6002 4050);
DISPLAY 0.872340 (-6002 4050);
PAINT GREEN (-6002 4050);
DISPLAY INVISIBLE (-6002 4050);
FORCEADD TAP..1
(-6000 4200);
FORCEPROP 3 LASTPIN (-6050 4200) SIG_NAME M_I_CPU0_SA_DQ<6>
J 0
(-6040 4210);
DISPLAY 0.659574 (-6040 4210);
PAINT MONO (-6040 4210);
DISPLAY INVISIBLE (-6040 4210);
FORCEPROP 1 LASTPIN (-6050 4200) BN 6
J 0
(-6062 4208);
DISPLAY 0.489362 (-6062 4208);
PAINT GREEN (-6062 4208);
FORCEPROP 2 LAST CDS_LIB mstr_standard
J 0
(-6000 4200);
DISPLAY 0.723404 (-6000 4200);
PAINT MONO (-6000 4200);
DISPLAY INVISIBLE (-6000 4200);
FORCEPROP 1 LAST BODY_TYPE PLUMBING
J 0
(-6000 4250);
DISPLAY 0.872340 (-6000 4250);
PAINT GREEN (-6000 4250);
DISPLAY INVISIBLE (-6000 4250);
FORCEPROP 1 LAST HDL_TAP TRUE
J 0
(-5675 4075);
DISPLAY 0.872340 (-5675 4075);
DISPLAY INVISIBLE (-5675 4075);
FORCEPROP 1 LAST PATH I97
J 0
(-6002 4200);
DISPLAY 0.872340 (-6002 4200);
PAINT GREEN (-6002 4200);
DISPLAY INVISIBLE (-6002 4200);
FORCEADD TAP..1
(-6000 4100);
FORCEPROP 3 LASTPIN (-6050 4100) SIG_NAME M_I_CPU0_SA_DQ<4>
J 0
(-6040 4110);
DISPLAY 0.659574 (-6040 4110);
PAINT MONO (-6040 4110);
DISPLAY INVISIBLE (-6040 4110);
FORCEPROP 1 LASTPIN (-6050 4100) BN 4
J 0
(-6062 4108);
DISPLAY 0.489362 (-6062 4108);
PAINT GREEN (-6062 4108);
FORCEPROP 2 LAST CDS_LIB mstr_standard
J 0
(-6000 4100);
DISPLAY 0.723404 (-6000 4100);
PAINT MONO (-6000 4100);
DISPLAY INVISIBLE (-6000 4100);
FORCEPROP 1 LAST BODY_TYPE PLUMBING
J 0
(-6000 4150);
DISPLAY 0.872340 (-6000 4150);
PAINT GREEN (-6000 4150);
DISPLAY INVISIBLE (-6000 4150);
FORCEPROP 1 LAST HDL_TAP TRUE
J 0
(-5675 3975);
DISPLAY 0.872340 (-5675 3975);
DISPLAY INVISIBLE (-5675 3975);
FORCEPROP 1 LAST PATH I98
J 0
(-6002 4100);
DISPLAY 0.872340 (-6002 4100);
PAINT GREEN (-6002 4100);
DISPLAY INVISIBLE (-6002 4100);
FORCEADD TAP..1
(-6000 4150);
FORCEPROP 3 LASTPIN (-6050 4150) SIG_NAME M_I_CPU0_SA_DQ<5>
J 0
(-6040 4160);
DISPLAY 0.659574 (-6040 4160);
PAINT MONO (-6040 4160);
DISPLAY INVISIBLE (-6040 4160);
FORCEPROP 1 LASTPIN (-6050 4150) BN 5
J 0
(-6062 4158);
DISPLAY 0.489362 (-6062 4158);
PAINT GREEN (-6062 4158);
FORCEPROP 2 LAST CDS_LIB mstr_standard
J 0
(-6000 4150);
DISPLAY 0.723404 (-6000 4150);
PAINT MONO (-6000 4150);
DISPLAY INVISIBLE (-6000 4150);
FORCEPROP 1 LAST BODY_TYPE PLUMBING
J 0
(-6000 4200);
DISPLAY 0.872340 (-6000 4200);
PAINT GREEN (-6000 4200);
DISPLAY INVISIBLE (-6000 4200);
FORCEPROP 1 LAST HDL_TAP TRUE
J 0
(-5675 4025);
DISPLAY 0.872340 (-5675 4025);
DISPLAY INVISIBLE (-5675 4025);
FORCEPROP 1 LAST PATH I99
J 0
(-6002 4150);
DISPLAY 0.872340 (-6002 4150);
PAINT GREEN (-6002 4150);
DISPLAY INVISIBLE (-6002 4150);
FORCEADD DNS..2
(-8325 2350);
PAINT RED (-8325 2350);
FORCEPROP 2 LAST CDS_LIB mstr_misc
J 0
(-8325 2350);
DISPLAY INVISIBLE (-8325 2350);
FORCEPROP 1 LAST COMMENT_BODY TRUE
R 1
J 0
(-8250 2125);
DISPLAY 0.872340 (-8250 2125);
PAINT PEACH (-8250 2125);
DISPLAY INVISIBLE (-8250 2125);
FORCEADD QUANTA_TITLE_BLOCK_C..1
(0 0);
FORCEPROP 0 LAST CDS_CON_LAST_MODIFIED Fri Mar 11 14:52:58 2022
J 0
(-1885 15);
DISPLAY INVISIBLE (-1885 15);
FORCEPROP 1 LAST CUSTOM_TXT_CDS <CON_LAST_MODIFIED>
J 0
(-1885 15);
DISPLAY 0.978723 (-1885 15);
FORCEPROP 2 LAST CUSTOM_TXT_CDS <XR_PAGE_TITLE>
J 0
(-7890 5250);
DISPLAY 0.638298 (-7890 5250);
PAINT PINK (-7890 5250);
DISPLAY INVISIBLE (-7890 5250);
FORCEPROP 1 LAST CUSTOM_TXT_CDS <NAME_2>
J 0
(-3175 50);
FORCEPROP 1 LAST CUSTOM_TXT_CDS <NAME_1>
J 0
(-3175 175);
FORCEPROP 1 LAST CUSTOM_TXT_CDS <Q_NUMBER>
J 0
(-1403 103);
DISPLAY 1.212766 (-1403 103);
FORCEPROP 1 LAST CUSTOM_TXT_CDS <Q_PROJ>
J 0
(-2382 102);
DISPLAY 1.212766 (-2382 102);
FORCEPROP 1 LAST CUSTOM_TXT_CDS <Q_REV>
J 0
(-184 103);
DISPLAY 1.212766 (-184 103);
FORCEPROP 1 LAST CUSTOM_TXT_CDS <CON_PAGE_NUM> OF <CON_TOTAL_PAGES>
J 0
(-446 18);
DISPLAY 0.978723 (-446 18);
FORCEPROP 1 LAST Q_TITLE DDR5 - CPU0 CHI
J 0
(-9325 50);
DISPLAY 2.446809 (-9325 50);
PAINT GREEN (-9325 50);
FORCEPROP 1 LAST Q_DEPT BU9
J 1
(-3763 49);
DISPLAY 1.957447 (-3763 49);
PAINT GREEN (-3763 49);
FORCEPROP 2 LAST CDS_LIB pure_quanta
J 0
(0 0);
DISPLAY INVISIBLE (0 0);
FORCEPROP 1 LAST CDS_LMAN_SYM_OUTLINE -9475,6775,100,-125
J 0
(0 0);
DISPLAY 0.468085 (0 0);
PAINT GREEN (0 0);
DISPLAY INVISIBLE (0 0);
FORCEPROP 2 LAST PAGE_BORDER TRUE
J 0
(-7890 5250);
DISPLAY 0.638298 (-7890 5250);
PAINT PINK (-7890 5250);
DISPLAY INVISIBLE (-7890 5250);
FORCEPROP 1 LAST COMMENT_BODY TRUE
J 0
(12 -13);
DISPLAY 0.978723 (12 -13);
PAINT GREEN (12 -13);
DISPLAY INVISIBLE (12 -13);
FORCEPROP 2 LAST CDS_XR_PAGE_TITLE CR-93 : @T6G_MB_LIB.T6G(SCH_1):PAGE93
J 0
(-7890 5250);
DISPLAY 0.638298 (-7890 5250);
PAINT PINK (-7890 5250);
DISPLAY INVISIBLE (-7890 5250);
WIRE 17 -1 (-5950 5475)(-5950 5425);
WIRE 17 -1 (-5950 5475)(-5375 5475);
FORCEPROP 2 LAST SIG_NAME M_I_CPU0_SA_DQ<31:0>
J 0
(-5885 5485);
DISPLAY 0.489362 (-5885 5485);
WIRE 17 -1 (-7750 4075)(-7750 4025);
WIRE 17 -1 (-7750 4075)(-7750 4100);
WIRE 17 -1 (-7750 3975)(-7750 4025);
WIRE 17 -1 (-7750 3975)(-7750 3925);
WIRE 17 -1 (-7750 4100)(-8250 4100);
FORCEPROP 2 LAST SIG_NAME M_I_CPU0_SA_CB<7:0>
J 0
(-8200 4110);
DISPLAY 0.489362 (-8200 4110);
WIRE 17 -1 (-7750 3875)(-7750 3925);
WIRE 17 -1 (-7750 3825)(-7750 3875);
WIRE 17 -1 (-7750 3775)(-7750 3825);
WIRE 17 -1 (-7750 3725)(-7750 3775);
WIRE 17 -1 (-7750 3625)(-7750 3575);
WIRE 17 -1 (-7750 3625)(-7750 3650);
WIRE 17 -1 (-7750 3525)(-7750 3575);
WIRE 17 -1 (-7750 3525)(-7750 3475);
WIRE 17 -1 (-7750 3650)(-8250 3650);
FORCEPROP 2 LAST SIG_NAME M_I_CPU0_SB_CB<7:0>
J 0
(-8200 3660);
DISPLAY 0.489362 (-8200 3660);
WIRE 17 -1 (-7750 5175)(-7750 5225);
WIRE 17 -1 (-7750 5225)(-7750 5275);
WIRE 17 -1 (-7750 5275)(-7750 5325);
WIRE 17 -1 (-7750 5325)(-7750 5375);
WIRE 17 -1 (-7750 5375)(-7750 5425);
WIRE 17 -1 (-7750 5425)(-7750 5475);
WIRE 17 -1 (-7750 5475)(-7750 5500);
WIRE 17 -1 (-7750 5500)(-8250 5500);
FORCEPROP 2 LAST SIG_NAME M_I_CPU0_SA_CA<6:0>
J 0
(-8235 5510);
DISPLAY 0.489362 (-8235 5510);
WIRE 17 -1 (-7750 4775)(-7750 4825);
WIRE 17 -1 (-7750 4825)(-7750 4875);
WIRE 17 -1 (-7750 4875)(-7750 4925);
WIRE 17 -1 (-7750 4925)(-7750 4975);
WIRE 17 -1 (-7750 4975)(-7750 5025);
WIRE 17 -1 (-7750 5025)(-7750 5075);
WIRE 17 -1 (-7750 5075)(-7750 5100);
WIRE 17 -1 (-7750 5100)(-8250 5100);
FORCEPROP 2 LAST SIG_NAME M_I_CPU0_SB_CA<6:0>
J 0
(-8235 5110);
DISPLAY 0.489362 (-8235 5110);
WIRE 17 -1 (-7750 3425)(-7750 3475);
WIRE 17 -1 (-7750 3375)(-7750 3425);
WIRE 17 -1 (-7750 3325)(-7750 3375);
WIRE 17 -1 (-7750 3275)(-7750 3325);
WIRE 17 -1 (-5950 5425)(-5950 5375);
WIRE 17 -1 (-5950 5375)(-5950 5325);
WIRE 17 -1 (-5950 5325)(-5950 5275);
WIRE 17 -1 (-5950 5275)(-5950 5225);
WIRE 17 -1 (-5950 5225)(-5950 5175);
WIRE 17 -1 (-5950 5175)(-5950 5125);
WIRE 17 -1 (-5950 5125)(-5950 5075);
WIRE 17 -1 (-5950 5075)(-5950 5025);
WIRE 17 -1 (-5950 5025)(-5950 4975);
WIRE 17 -1 (-5950 4975)(-5950 4925);
WIRE 17 -1 (-5950 4925)(-5950 4875);
WIRE 17 -1 (-5950 4875)(-5950 4825);
WIRE 17 -1 (-5950 4825)(-5950 4775);
WIRE 17 -1 (-5950 4775)(-5950 4725);
WIRE 17 -1 (-5950 4675)(-5950 4725);
WIRE 17 -1 (-5950 4625)(-5950 4675);
WIRE 17 -1 (-5950 4575)(-5950 4625);
WIRE 17 -1 (-5950 4525)(-5950 4575);
WIRE 17 -1 (-5950 4525)(-5950 4475);
WIRE 17 -1 (-5950 4475)(-5950 4425);
WIRE 17 -1 (-5950 4425)(-5950 4375);
WIRE 17 -1 (-5950 4375)(-5950 4325);
WIRE 17 -1 (-5950 4325)(-5950 4275);
WIRE 17 -1 (-5950 4275)(-5950 4225);
WIRE 17 -1 (-5950 4225)(-5950 4175);
WIRE 17 -1 (-5950 4175)(-5950 4125);
WIRE 17 -1 (-5950 4075)(-5950 4125);
WIRE 17 -1 (-5950 4025)(-5950 4075);
WIRE 17 -1 (-5950 3975)(-5950 4025);
WIRE 17 -1 (-5950 3925)(-5950 3975);
WIRE 17 -1 (-5950 3825)(-5950 3775);
WIRE 17 -1 (-5950 3825)(-5375 3825);
FORCEPROP 2 LAST SIG_NAME M_I_CPU0_SB_DQ<31:0>
J 0
(-5885 3835);
DISPLAY 0.489362 (-5885 3835);
WIRE 17 -1 (-5950 3775)(-5950 3725);
WIRE 17 -1 (-5950 3725)(-5950 3675);
WIRE 17 -1 (-5950 3675)(-5950 3625);
WIRE 17 -1 (-5950 3625)(-5950 3575);
WIRE 17 -1 (-5950 3575)(-5950 3525);
WIRE 17 -1 (-5950 3525)(-5950 3475);
WIRE 17 -1 (-5950 3475)(-5950 3425);
WIRE 17 -1 (-5950 3425)(-5950 3375);
WIRE 17 -1 (-5950 3375)(-5950 3325);
WIRE 17 -1 (-5950 3325)(-5950 3275);
WIRE 17 -1 (-5950 3275)(-5950 3225);
WIRE 17 -1 (-5950 3225)(-5950 3175);
WIRE 17 -1 (-5950 3175)(-5950 3125);
WIRE 17 -1 (-5950 3125)(-5950 3075);
WIRE 17 -1 (-5950 3025)(-5950 3075);
WIRE 17 -1 (-5950 2975)(-5950 3025);
WIRE 17 -1 (-5950 2925)(-5950 2975);
WIRE 17 -1 (-5950 2875)(-5950 2925);
WIRE 17 -1 (-5950 2875)(-5950 2825);
WIRE 17 -1 (-5950 2825)(-5950 2775);
WIRE 17 -1 (-5950 2775)(-5950 2725);
WIRE 17 -1 (-5950 2725)(-5950 2675);
WIRE 17 -1 (-5950 2675)(-5950 2625);
WIRE 17 -1 (-5950 2625)(-5950 2575);
WIRE 17 -1 (-5950 2575)(-5950 2525);
WIRE 17 -1 (-5950 2525)(-5950 2475);
WIRE 17 -1 (-5950 2425)(-5950 2475);
WIRE 17 -1 (-5950 2375)(-5950 2425);
WIRE 17 -1 (-5950 2325)(-5950 2375);
WIRE 17 -1 (-5950 2275)(-5950 2325);
WIRE 17 -1 (-3200 4275)(-3200 4175);
WIRE 17 -1 (-3200 4375)(-3200 4275);
WIRE 17 -1 (-3200 4175)(-3200 4075);
WIRE 17 -1 (-3200 3975)(-3200 4075);
WIRE 17 -1 (-3200 4475)(-3200 4375);
WIRE 17 -1 (-3200 4500)(-3200 4475);
WIRE 17 -1 (-3200 3875)(-3200 3975);
WIRE 17 -1 (-3200 3775)(-3200 3875);
WIRE 17 -1 (-3200 4500)(-2500 4500);
FORCEPROP 2 LAST SIG_NAME M_I_CPU0_SA_DQS_DN<9:0>
J 0
(-3135 4510);
DISPLAY 0.489362 (-3135 4510);
WIRE 17 -1 (-3400 4225)(-3400 4125);
WIRE 17 -1 (-3400 4325)(-3400 4225);
WIRE 17 -1 (-3400 4025)(-3400 4125);
WIRE 17 -1 (-3400 3925)(-3400 4025);
WIRE 17 -1 (-3400 4425)(-3400 4325);
WIRE 17 -1 (-3400 4525)(-3400 4425);
WIRE 17 -1 (-3400 3825)(-3400 3925);
WIRE 17 -1 (-3400 3825)(-3400 3725);
WIRE 17 -1 (-3400 4550)(-3400 4525);
WIRE 17 -1 (-3400 4550)(-2500 4550);
FORCEPROP 2 LAST SIG_NAME M_I_CPU0_SA_DQS_DP<9:0>
J 0
(-3135 4560);
DISPLAY 0.489362 (-3135 4560);
WIRE 17 -1 (-3400 3375)(-3400 3275);
WIRE 17 -1 (-3400 3475)(-3400 3375);
WIRE 17 -1 (-3400 3275)(-3400 3175);
WIRE 17 -1 (-3400 3175)(-3400 3075);
WIRE 17 -1 (-3400 3500)(-3400 3475);
WIRE 17 -1 (-3400 3500)(-2500 3500);
FORCEPROP 2 LAST SIG_NAME M_I_CPU0_SB_DQS_DP<9:0>
J 0
(-3135 3510);
DISPLAY 0.489362 (-3135 3510);
WIRE 17 -1 (-3200 3325)(-3200 3225);
WIRE 17 -1 (-3200 3425)(-3200 3325);
WIRE 17 -1 (-3200 3225)(-3200 3125);
WIRE 17 -1 (-3200 3125)(-3200 3025);
WIRE 17 -1 (-3200 3450)(-3200 3425);
WIRE 17 -1 (-3200 3450)(-2500 3450);
FORCEPROP 2 LAST SIG_NAME M_I_CPU0_SB_DQS_DN<9:0>
J 0
(-3135 3460);
DISPLAY 0.489362 (-3135 3460);
WIRE 17 -1 (-3400 2975)(-3400 3075);
WIRE 17 -1 (-3400 2875)(-3400 2975);
WIRE 17 -1 (-3400 2775)(-3400 2875);
WIRE 17 -1 (-3200 3675)(-3200 3575);
WIRE 17 -1 (-3200 3775)(-3200 3675);
WIRE 17 -1 (-3400 3725)(-3400 3625);
WIRE 17 -1 (-3200 2625)(-3200 2525);
WIRE 17 -1 (-3200 2725)(-3200 2625);
WIRE 17 -1 (-3200 2725)(-3200 2825);
WIRE 17 -1 (-3200 2825)(-3200 2925);
WIRE 17 -1 (-3200 2925)(-3200 3025);
WIRE 17 -1 (-3400 2675)(-3400 2575);
WIRE 17 -1 (-3400 2775)(-3400 2675);
WIRE 16 -1 (-8650 3100)(-8650 3175);
WIRE 16 -1 (-8350 2450)(-8350 2475);
WIRE 16 -1 (-7850 2750)(-8250 2750);
FORCEPROP 2 LAST SIG_NAME I3C_SPD_DDRGL_CPU0_SCL
J 0
(-8310 2760);
DISPLAY 0.489362 (-8310 2760);
WIRE 16 -1 (-7550 2850)(-7550 2750);
WIRE 16 -1 (-7450 2850)(-7550 2850);
FORCEPROP 2 LAST SIG_NAME I3C_SPD_DDRI_CPU0_SCL
J 0
(-7935 2860);
DISPLAY 0.446809 (-7935 2860);
FORCEPROP 2 LASTPROP $XRERR UNIQUE?
J 0
(-8175 2860);
DISPLAY 0.638298 (-8175 2860);
PAINT MONO (-8175 2860);
DISPLAY INVISIBLE (-8175 2860);
WIRE 16 -1 (-7550 2750)(-7650 2750);
WIRE 16 -1 (-7450 2900)(-8250 2900);
FORCEPROP 2 LAST SIG_NAME I3C_SPD_DDRGL_CPU0_SDA
J 0
(-8260 2910);
DISPLAY 0.489362 (-8260 2910);
WIRE 16 -1 (-7450 2600)(-8150 2600);
FORCEPROP 2 LAST SIG_NAME PWRGD_CHI_CPU0_DIMM
J 0
(-8050 2610);
DISPLAY 0.489362 (-8050 2610);
FORCEPROP 2 LASTPROP $XRERR UNIQUE?
J 0
(-8290 2610);
DISPLAY 0.638298 (-8290 2610);
PAINT MONO (-8290 2610);
DISPLAY INVISIBLE (-8290 2610);
WIRE 16 -1 (-8150 2200)(-8150 2600);
WIRE 16 -1 (-8150 2200)(-8350 2200);
WIRE 16 -1 (-8350 2200)(-8375 2200);
WIRE 16 -1 (-8350 2250)(-8350 2200);
WIRE 16 -1 (-7450 2450)(-8075 2450);
FORCEPROP 2 LAST SIG_NAME TP_CHI_CPU0_DIMM_RFU_5
J 0
(-8085 2460);
DISPLAY 0.489362 (-8085 2460);
FORCEPROP 2 LASTPROP $XRERR UNIQUE?
J 0
(-8315 2450);
DISPLAY 0.638298 (-8315 2450);
PAINT MONO (-8315 2450);
DISPLAY INVISIBLE (-8315 2450);
WIRE 16 -1 (-7450 2250)(-8075 2250);
FORCEPROP 2 LAST SIG_NAME TP_CHI_CPU0_DIMM_RFU_1
J 0
(-8085 2260);
DISPLAY 0.489362 (-8085 2260);
FORCEPROP 2 LASTPROP $XRERR UNIQUE?
J 0
(-8315 2250);
DISPLAY 0.638298 (-8315 2250);
PAINT MONO (-8315 2250);
DISPLAY INVISIBLE (-8315 2250);
WIRE 16 -1 (-7450 2200)(-8075 2200);
FORCEPROP 2 LAST SIG_NAME TP_CHI_CPU0_DIMM_RFU_0
J 0
(-8085 2210);
DISPLAY 0.489362 (-8085 2210);
FORCEPROP 2 LASTPROP $XRERR UNIQUE?
J 0
(-8315 2200);
DISPLAY 0.638298 (-8315 2200);
PAINT MONO (-8315 2200);
DISPLAY INVISIBLE (-8315 2200);
WIRE 16 -1 (-7450 2050)(-8250 2050);
FORCEPROP 2 LAST SIG_NAME M_I_CPU0_SA_RSP<0>
J 0
(-8200 2060);
DISPLAY 0.489362 (-8200 2060);
WIRE 16 -1 (-7450 2000)(-8250 2000);
FORCEPROP 2 LAST SIG_NAME M_I_CPU0_SB_RSP<0>
J 0
(-8200 2010);
DISPLAY 0.489362 (-8200 2010);
WIRE 16 -1 (-6425 1475)(-6425 1400);
WIRE 16 -1 (-6425 1475)(-7150 1475);
FORCEPROP 2 LAST SIG_NAME PD_CHI_CPU0_DIMM_SAA
J 0
(-7135 1485);
DISPLAY 0.489362 (-7135 1485);
WIRE 16 -1 (-7450 2400)(-8075 2400);
FORCEPROP 2 LAST SIG_NAME TP_CHI_CPU0_DIMM_RFU_4
J 0
(-8085 2410);
DISPLAY 0.489362 (-8085 2410);
FORCEPROP 2 LASTPROP $XRERR UNIQUE?
J 0
(-8315 2400);
DISPLAY 0.638298 (-8315 2400);
PAINT MONO (-8315 2400);
DISPLAY INVISIBLE (-8315 2400);
WIRE 16 -1 (-2125 5350)(-1825 5350);
WIRE 16 -1 (-2125 5400)(-2125 5350);
WIRE 16 -1 (-1825 5400)(-2125 5400);
WIRE 16 -1 (-2125 5400)(-2125 5450);
WIRE 16 -1 (-1825 5450)(-2125 5450);
WIRE 16 -1 (-2125 5450)(-2125 6100);
WIRE 16 -1 (-2250 6100)(-2125 6100);
WIRE 16 -1 (-2250 6100)(-2825 6100);
WIRE 16 -1 (-2250 6100)(-2250 6000);
WIRE 16 -1 (-2825 6100)(-2825 6175);
WIRE 16 -1 (-2825 6000)(-2825 6100);
WIRE 16 -1 (-1825 5300)(-2125 5300);
WIRE 16 -1 (-2125 5300)(-2125 5250);
WIRE 16 -1 (-1825 5250)(-2125 5250);
WIRE 16 -1 (-2125 5250)(-2125 5200);
WIRE 16 -1 (-1825 5200)(-2125 5200);
WIRE 16 -1 (-2125 5200)(-2125 5150);
WIRE 16 -1 (-1825 5150)(-2125 5150);
WIRE 16 -1 (-2125 5150)(-2125 5100);
WIRE 16 -1 (-1825 5100)(-2125 5100);
WIRE 16 -1 (-2125 5100)(-2125 5050);
WIRE 16 -1 (-1825 5050)(-2125 5050);
WIRE 16 -1 (-2125 5050)(-2125 5000);
WIRE 16 -1 (-1825 5000)(-2125 5000);
WIRE 16 -1 (-2125 5000)(-2125 4950);
WIRE 16 -1 (-1825 4950)(-2125 4950);
WIRE 16 -1 (-2125 4950)(-2125 4900);
WIRE 16 -1 (-1825 4900)(-2125 4900);
WIRE 16 -1 (-2125 4900)(-2125 4850);
WIRE 16 -1 (-1825 4850)(-2125 4850);
WIRE 16 -1 (-2125 4850)(-2125 4800);
WIRE 16 -1 (-1825 4800)(-2125 4800);
WIRE 16 -1 (-2125 4800)(-2125 4750);
WIRE 16 -1 (-1825 4750)(-2125 4750);
WIRE 16 -1 (-2125 4750)(-2125 4700);
WIRE 16 -1 (-1825 4700)(-2125 4700);
WIRE 16 -1 (-2125 4700)(-2125 4650);
WIRE 16 -1 (-1825 4650)(-2125 4650);
WIRE 16 -1 (-2125 4650)(-2125 4600);
WIRE 16 -1 (-1825 4600)(-2125 4600);
WIRE 16 -1 (-2125 4600)(-2125 4550);
WIRE 16 -1 (-1825 4550)(-2125 4550);
WIRE 16 -1 (-2125 4550)(-2125 4500);
WIRE 16 -1 (-1825 4500)(-2125 4500);
WIRE 16 -1 (-2125 4500)(-2125 4450);
WIRE 16 -1 (-1825 4450)(-2125 4450);
WIRE 16 -1 (-2125 4450)(-2125 4400);
WIRE 16 -1 (-1825 4400)(-2125 4400);
WIRE 16 -1 (-2125 4400)(-2125 4350);
WIRE 16 -1 (-1825 4350)(-2125 4350);
WIRE 16 -1 (-2125 4350)(-2125 4300);
WIRE 16 -1 (-1825 4300)(-2125 4300);
WIRE 16 -1 (-2125 4300)(-2125 4250);
WIRE 16 -1 (-1825 4250)(-2125 4250);
WIRE 16 -1 (-2125 4250)(-2125 4200);
WIRE 16 -1 (-1825 4200)(-2125 4200);
WIRE 16 -1 (-2125 4200)(-2125 4150);
WIRE 16 -1 (-1825 4150)(-2125 4150);
WIRE 16 -1 (-2125 4150)(-2125 4100);
WIRE 16 -1 (-1825 4100)(-2125 4100);
WIRE 16 -1 (-2125 4100)(-2125 4050);
WIRE 16 -1 (-1825 4050)(-2125 4050);
WIRE 16 -1 (-2125 4050)(-2125 4000);
WIRE 16 -1 (-1825 4000)(-2125 4000);
WIRE 16 -1 (-2125 4000)(-2125 3950);
WIRE 16 -1 (-1825 3950)(-2125 3950);
WIRE 16 -1 (-2125 3950)(-2125 3900);
WIRE 16 -1 (-1825 3900)(-2125 3900);
WIRE 16 -1 (-2125 3900)(-2125 3850);
WIRE 16 -1 (-1825 3850)(-2125 3850);
WIRE 16 -1 (-2125 3850)(-2125 3800);
WIRE 16 -1 (-1825 3800)(-2125 3800);
WIRE 16 -1 (-2125 3800)(-2125 3750);
WIRE 16 -1 (-1825 3750)(-2125 3750);
WIRE 16 -1 (-2125 3750)(-2125 3700);
WIRE 16 -1 (-1825 3700)(-2125 3700);
WIRE 16 -1 (-2125 3700)(-2125 3650);
WIRE 16 -1 (-1825 3650)(-2125 3650);
WIRE 16 -1 (-2125 3650)(-2125 3600);
WIRE 16 -1 (-1825 3600)(-2125 3600);
WIRE 16 -1 (-2125 3600)(-2125 3550);
WIRE 16 -1 (-1825 3550)(-2125 3550);
WIRE 16 -1 (-2125 3550)(-2125 3500);
WIRE 16 -1 (-1825 3500)(-2125 3500);
WIRE 16 -1 (-2125 3500)(-2125 3450);
WIRE 16 -1 (-1825 3450)(-2125 3450);
WIRE 16 -1 (-2125 3450)(-2125 3400);
WIRE 16 -1 (-1825 3400)(-2125 3400);
WIRE 16 -1 (-2125 3400)(-2125 3350);
WIRE 16 -1 (-1825 3350)(-2125 3350);
WIRE 16 -1 (-2125 3350)(-2125 3300);
WIRE 16 -1 (-1825 3300)(-2125 3300);
WIRE 16 -1 (-2125 3300)(-2125 3250);
WIRE 16 -1 (-1825 3250)(-2125 3250);
WIRE 16 -1 (-2125 3250)(-2125 3200);
WIRE 16 -1 (-1825 3200)(-2125 3200);
WIRE 16 -1 (-2125 3200)(-2125 3150);
WIRE 16 -1 (-1825 3150)(-2125 3150);
WIRE 16 -1 (-2125 3150)(-2125 3100);
WIRE 16 -1 (-1825 3100)(-2125 3100);
WIRE 16 -1 (-2125 3100)(-2125 3050);
WIRE 16 -1 (-1825 3050)(-2125 3050);
WIRE 16 -1 (-2125 3050)(-2125 3000);
WIRE 16 -1 (-1825 3000)(-2125 3000);
WIRE 16 -1 (-2125 3000)(-2125 2950);
WIRE 16 -1 (-1825 2950)(-2125 2950);
WIRE 16 -1 (-2125 2950)(-2125 2900);
WIRE 16 -1 (-1825 2900)(-2125 2900);
WIRE 16 -1 (-2125 2900)(-2125 2850);
WIRE 16 -1 (-1825 2850)(-2125 2850);
WIRE 16 -1 (-2125 2850)(-2125 2800);
WIRE 16 -1 (-1825 2800)(-2125 2800);
WIRE 16 -1 (-2125 2800)(-2125 2750);
WIRE 16 -1 (-1825 2750)(-2125 2750);
WIRE 16 -1 (-2125 2750)(-2125 2700);
WIRE 16 -1 (-1825 2700)(-2125 2700);
WIRE 16 -1 (-2125 2700)(-2125 2650);
WIRE 16 -1 (-1825 2650)(-2125 2650);
WIRE 16 -1 (-2125 2650)(-2125 2600);
WIRE 16 -1 (-1825 2600)(-2125 2600);
WIRE 16 -1 (-2125 2600)(-2125 2550);
WIRE 16 -1 (-1825 2550)(-2125 2550);
WIRE 16 -1 (-2125 2550)(-2125 2500);
WIRE 16 -1 (-1825 2500)(-2125 2500);
WIRE 16 -1 (-2125 2500)(-2125 2450);
WIRE 16 -1 (-1825 2450)(-2125 2450);
WIRE 16 -1 (-2125 2450)(-2125 2400);
WIRE 16 -1 (-1825 2400)(-2125 2400);
WIRE 16 -1 (-2125 2400)(-2125 2350);
WIRE 16 -1 (-1825 2350)(-2125 2350);
WIRE 16 -1 (-2125 2350)(-2125 2300);
WIRE 16 -1 (-1825 2300)(-2125 2300);
WIRE 16 -1 (-2125 2300)(-2125 2250);
WIRE 16 -1 (-2125 2250)(-2125 2200);
WIRE 16 -1 (-1825 2250)(-2125 2250);
WIRE 16 -1 (-1825 2200)(-2125 2200);
WIRE 16 -1 (-2125 2200)(-2125 2075);
WIRE 16 -1 (-325 5450)(-325 5400);
WIRE 16 -1 (-325 5450)(-625 5450);
WIRE 16 -1 (-325 5400)(-325 5350);
WIRE 16 -1 (-325 5400)(-625 5400);
WIRE 16 -1 (-325 5350)(-325 5300);
WIRE 16 -1 (-325 5350)(-625 5350);
WIRE 16 -1 (-325 5300)(-325 5250);
WIRE 16 -1 (-325 5300)(-625 5300);
WIRE 16 -1 (-325 5250)(-325 5200);
WIRE 16 -1 (-325 5250)(-625 5250);
WIRE 16 -1 (-325 5200)(-325 5150);
WIRE 16 -1 (-325 5200)(-625 5200);
WIRE 16 -1 (-325 5150)(-625 5150);
WIRE 16 -1 (-325 5150)(-325 5100);
WIRE 16 -1 (-325 5100)(-325 5050);
WIRE 16 -1 (-325 5100)(-625 5100);
WIRE 16 -1 (-325 5050)(-325 5000);
WIRE 16 -1 (-325 5050)(-625 5050);
WIRE 16 -1 (-325 5000)(-325 4950);
WIRE 16 -1 (-325 5000)(-625 5000);
WIRE 16 -1 (-325 4950)(-325 4900);
WIRE 16 -1 (-325 4950)(-625 4950);
WIRE 16 -1 (-325 4900)(-325 4850);
WIRE 16 -1 (-325 4900)(-625 4900);
WIRE 16 -1 (-325 4850)(-325 4800);
WIRE 16 -1 (-325 4850)(-625 4850);
WIRE 16 -1 (-325 4800)(-325 4750);
WIRE 16 -1 (-325 4800)(-625 4800);
WIRE 16 -1 (-325 4750)(-325 4700);
WIRE 16 -1 (-325 4750)(-625 4750);
WIRE 16 -1 (-325 4700)(-325 4650);
WIRE 16 -1 (-325 4700)(-625 4700);
WIRE 16 -1 (-325 4650)(-325 4600);
WIRE 16 -1 (-325 4650)(-625 4650);
WIRE 16 -1 (-325 4600)(-325 4550);
WIRE 16 -1 (-325 4600)(-625 4600);
WIRE 16 -1 (-325 4550)(-325 4500);
WIRE 16 -1 (-325 4550)(-625 4550);
WIRE 16 -1 (-325 4500)(-325 4450);
WIRE 16 -1 (-325 4500)(-625 4500);
WIRE 16 -1 (-325 4450)(-325 4400);
WIRE 16 -1 (-325 4450)(-625 4450);
WIRE 16 -1 (-325 4400)(-325 4350);
WIRE 16 -1 (-325 4400)(-625 4400);
WIRE 16 -1 (-325 4350)(-325 4300);
WIRE 16 -1 (-325 4350)(-625 4350);
WIRE 16 -1 (-325 4300)(-325 4250);
WIRE 16 -1 (-325 4300)(-625 4300);
WIRE 16 -1 (-325 4250)(-325 4200);
WIRE 16 -1 (-325 4250)(-625 4250);
WIRE 16 -1 (-325 4200)(-325 4150);
WIRE 16 -1 (-325 4200)(-625 4200);
WIRE 16 -1 (-325 4150)(-325 4100);
WIRE 16 -1 (-325 4150)(-625 4150);
WIRE 16 -1 (-325 4100)(-625 4100);
WIRE 16 -1 (-325 4100)(-325 4050);
WIRE 16 -1 (-325 4050)(-325 4000);
WIRE 16 -1 (-325 4050)(-625 4050);
WIRE 16 -1 (-325 4000)(-325 3950);
WIRE 16 -1 (-325 4000)(-625 4000);
WIRE 16 -1 (-325 3950)(-325 3900);
WIRE 16 -1 (-325 3950)(-625 3950);
WIRE 16 -1 (-325 3900)(-325 3850);
WIRE 16 -1 (-325 3900)(-625 3900);
WIRE 16 -1 (-325 3850)(-325 3800);
WIRE 16 -1 (-325 3850)(-625 3850);
WIRE 16 -1 (-325 3800)(-325 3750);
WIRE 16 -1 (-325 3800)(-625 3800);
WIRE 16 -1 (-325 3750)(-325 3700);
WIRE 16 -1 (-325 3750)(-625 3750);
WIRE 16 -1 (-325 3700)(-325 3650);
WIRE 16 -1 (-325 3700)(-625 3700);
WIRE 16 -1 (-325 3650)(-325 3600);
WIRE 16 -1 (-325 3650)(-625 3650);
WIRE 16 -1 (-325 3600)(-325 3550);
WIRE 16 -1 (-325 3600)(-625 3600);
WIRE 16 -1 (-325 3550)(-325 3500);
WIRE 16 -1 (-325 3550)(-625 3550);
WIRE 16 -1 (-325 3500)(-325 3450);
WIRE 16 -1 (-325 3500)(-625 3500);
WIRE 16 -1 (-325 3450)(-325 3400);
WIRE 16 -1 (-325 3450)(-625 3450);
WIRE 16 -1 (-325 3400)(-325 3350);
WIRE 16 -1 (-325 3400)(-625 3400);
WIRE 16 -1 (-325 3350)(-325 3300);
WIRE 16 -1 (-325 3350)(-625 3350);
WIRE 16 -1 (-325 3300)(-325 3250);
WIRE 16 -1 (-325 3300)(-625 3300);
WIRE 16 -1 (-325 3250)(-325 3200);
WIRE 16 -1 (-325 3250)(-625 3250);
WIRE 16 -1 (-325 3200)(-325 3150);
WIRE 16 -1 (-325 3200)(-625 3200);
WIRE 16 -1 (-325 3150)(-325 3100);
WIRE 16 -1 (-325 3150)(-625 3150);
WIRE 16 -1 (-325 3100)(-625 3100);
WIRE 16 -1 (-325 3100)(-325 3050);
WIRE 16 -1 (-325 3050)(-325 3000);
WIRE 16 -1 (-325 3050)(-625 3050);
WIRE 16 -1 (-325 3000)(-325 2950);
WIRE 16 -1 (-325 3000)(-625 3000);
WIRE 16 -1 (-325 2950)(-325 2900);
WIRE 16 -1 (-325 2950)(-625 2950);
WIRE 16 -1 (-325 2900)(-325 2850);
WIRE 16 -1 (-325 2900)(-625 2900);
WIRE 16 -1 (-325 2850)(-325 2800);
WIRE 16 -1 (-325 2850)(-625 2850);
WIRE 16 -1 (-325 2800)(-325 2750);
WIRE 16 -1 (-325 2800)(-625 2800);
WIRE 16 -1 (-325 2750)(-325 2700);
WIRE 16 -1 (-325 2750)(-625 2750);
WIRE 16 -1 (-325 2700)(-325 2650);
WIRE 16 -1 (-325 2700)(-625 2700);
WIRE 16 -1 (-325 2650)(-325 2600);
WIRE 16 -1 (-325 2650)(-625 2650);
WIRE 16 -1 (-325 2600)(-325 2550);
WIRE 16 -1 (-325 2600)(-625 2600);
WIRE 16 -1 (-325 2550)(-325 2500);
WIRE 16 -1 (-325 2550)(-625 2550);
WIRE 16 -1 (-325 2500)(-325 2450);
WIRE 16 -1 (-325 2500)(-625 2500);
WIRE 16 -1 (-325 2450)(-325 2400);
WIRE 16 -1 (-325 2450)(-625 2450);
WIRE 16 -1 (-325 2400)(-325 2350);
WIRE 16 -1 (-325 2400)(-625 2400);
WIRE 16 -1 (-325 2350)(-325 2300);
WIRE 16 -1 (-325 2350)(-625 2350);
WIRE 16 -1 (-325 2300)(-325 2200);
WIRE 16 -1 (-325 2300)(-625 2300);
WIRE 16 -1 (-325 2200)(-325 2150);
WIRE 16 -1 (-325 2200)(-625 2200);
WIRE 16 -1 (-325 2150)(-325 2100);
WIRE 16 -1 (-325 2150)(-625 2150);
WIRE 16 -1 (-325 2100)(-625 2100);
WIRE 16 -1 (-325 2100)(-325 1850);
WIRE 16 -1 (-3650 3450)(-3500 3450);
WIRE 16 -1 (-3650 3400)(-3300 3400);
WIRE 16 -1 (-3650 4500)(-3500 4500);
WIRE 16 -1 (-3650 4450)(-3300 4450);
WIRE 16 -1 (-3500 4400)(-3650 4400);
WIRE 16 -1 (-3650 4350)(-3300 4350);
WIRE 16 -1 (-3650 3200)(-3300 3200);
WIRE 16 -1 (-3500 4300)(-3650 4300);
WIRE 16 -1 (-3500 3150)(-3650 3150);
WIRE 16 -1 (-3650 3100)(-3300 3100);
WIRE 16 -1 (-3650 4150)(-3300 4150);
WIRE 16 -1 (-3650 3050)(-3500 3050);
WIRE 16 -1 (-3650 3000)(-3300 3000);
WIRE 16 -1 (-3650 4100)(-3500 4100);
WIRE 16 -1 (-3650 4050)(-3300 4050);
WIRE 16 -1 (-3500 2950)(-3650 2950);
WIRE 16 -1 (-3650 2900)(-3300 2900);
WIRE 16 -1 (-3500 4000)(-3650 4000);
WIRE 16 -1 (-3650 3950)(-3300 3950);
WIRE 16 -1 (-3500 2850)(-3650 2850);
WIRE 16 -1 (-3650 2800)(-3300 2800);
WIRE 16 -1 (-3500 3900)(-3650 3900);
WIRE 16 -1 (-3650 3850)(-3300 3850);
WIRE 16 -1 (-3500 2750)(-3650 2750);
WIRE 16 -1 (-3650 2700)(-3300 2700);
WIRE 16 -1 (-3500 3800)(-3650 3800);
WIRE 16 -1 (-3650 3750)(-3300 3750);
WIRE 16 -1 (-3650 2650)(-3500 2650);
WIRE 16 -1 (-3650 2600)(-3300 2600);
WIRE 16 -1 (-3650 3700)(-3500 3700);
WIRE 16 -1 (-3650 3650)(-3300 3650);
WIRE 16 -1 (-3500 2550)(-3650 2550);
WIRE 16 -1 (-3650 2500)(-3300 2500);
WIRE 16 -1 (-3500 3600)(-3650 3600);
WIRE 16 -1 (-3650 3550)(-3300 3550);
WIRE 16 -1 (-3500 3250)(-3650 3250);
WIRE 16 -1 (-3650 3300)(-3300 3300);
WIRE 16 -1 (-3500 3350)(-3650 3350);
WIRE 16 -1 (-3500 4200)(-3650 4200);
WIRE 16 -1 (-3650 4250)(-3300 4250);
WIRE 16 -1 (-8550 3000)(-7450 3000);
WIRE 16 -1 (-8550 3400)(-8550 3000);
WIRE 16 -1 (-8550 3425)(-8550 3400);
WIRE 16 -1 (-8650 3400)(-8550 3400);
WIRE 16 -1 (-8650 3375)(-8650 3400);
WIRE 16 -1 (-7450 2300)(-8075 2300);
FORCEPROP 2 LAST SIG_NAME TP_CHI_CPU0_DIMM_RFU_2
J 0
(-8085 2310);
DISPLAY 0.489362 (-8085 2310);
FORCEPROP 2 LASTPROP $XRERR UNIQUE?
J 0
(-8315 2300);
DISPLAY 0.638298 (-8315 2300);
PAINT MONO (-8315 2300);
DISPLAY INVISIBLE (-8315 2300);
WIRE 16 -1 (-7450 2350)(-8075 2350);
FORCEPROP 2 LAST SIG_NAME TP_CHI_CPU0_DIMM_RFU_3
J 0
(-8085 2360);
DISPLAY 0.489362 (-8085 2360);
FORCEPROP 2 LASTPROP $XRERR UNIQUE?
J 0
(-8315 2350);
DISPLAY 0.638298 (-8315 2350);
PAINT MONO (-8315 2350);
DISPLAY INVISIBLE (-8315 2350);
WIRE 16 -1 (-7450 2500)(-8075 2500);
FORCEPROP 2 LAST SIG_NAME TP_CHI_CPU0_DIMM_RFU_6
J 0
(-8085 2510);
DISPLAY 0.489362 (-8085 2510);
FORCEPROP 2 LASTPROP $XRERR UNIQUE?
J 0
(-8315 2500);
DISPLAY 0.638298 (-8315 2500);
PAINT MONO (-8315 2500);
DISPLAY INVISIBLE (-8315 2500);
WIRE 16 -1 (-7450 3150)(-8075 3150);
FORCEPROP 2 LAST SIG_NAME M_I_CPU0_RESET_N
J 0
(-8060 3160);
DISPLAY 0.489362 (-8060 3160);
WIRE 16 -1 (-7450 4600)(-8250 4600);
FORCEPROP 2 LAST SIG_NAME M_I_CPU0_SB_PAR
J 0
(-8200 4610);
DISPLAY 0.489362 (-8200 4610);
WIRE 16 -1 (-7450 4650)(-8250 4650);
FORCEPROP 2 LAST SIG_NAME M_I_CPU0_SA_PAR
J 0
(-8200 4660);
DISPLAY 0.489362 (-8200 4660);
WIRE 16 -1 (-7450 2950)(-8250 2950);
FORCEPROP 2 LAST SIG_NAME PD_CHI_CPU0_DIMM_SAA
J 0
(-8225 2960);
DISPLAY 0.489362 (-8225 2960);
WIRE 16 -1 (-6050 2250)(-6250 2250);
WIRE 16 -1 (-6050 2300)(-6250 2300);
WIRE 16 -1 (-6050 2350)(-6250 2350);
WIRE 16 -1 (-6250 2400)(-6050 2400);
WIRE 16 -1 (-6050 2450)(-6250 2450);
WIRE 16 -1 (-6050 2500)(-6250 2500);
WIRE 16 -1 (-6050 2550)(-6250 2550);
WIRE 16 -1 (-6250 2600)(-6050 2600);
WIRE 16 -1 (-6050 2650)(-6250 2650);
WIRE 16 -1 (-6050 2700)(-6250 2700);
WIRE 16 -1 (-6050 2750)(-6250 2750);
WIRE 16 -1 (-6250 2800)(-6050 2800);
WIRE 16 -1 (-6050 2850)(-6250 2850);
WIRE 16 -1 (-6050 2900)(-6250 2900);
WIRE 16 -1 (-6050 2950)(-6250 2950);
WIRE 16 -1 (-6250 3000)(-6050 3000);
WIRE 16 -1 (-6050 3050)(-6250 3050);
WIRE 16 -1 (-6050 3100)(-6250 3100);
WIRE 16 -1 (-6050 3150)(-6250 3150);
WIRE 16 -1 (-6250 3200)(-6050 3200);
WIRE 16 -1 (-6050 3250)(-6250 3250);
WIRE 16 -1 (-6050 3300)(-6250 3300);
WIRE 16 -1 (-6050 3350)(-6250 3350);
WIRE 16 -1 (-6250 3400)(-6050 3400);
WIRE 16 -1 (-6050 3450)(-6250 3450);
WIRE 16 -1 (-6050 3500)(-6250 3500);
WIRE 16 -1 (-6050 3550)(-6250 3550);
WIRE 16 -1 (-6250 3600)(-6050 3600);
WIRE 16 -1 (-6050 3650)(-6250 3650);
WIRE 16 -1 (-6050 3700)(-6250 3700);
WIRE 16 -1 (-6050 3750)(-6250 3750);
WIRE 16 -1 (-6250 3800)(-6050 3800);
WIRE 16 -1 (-6050 3900)(-6250 3900);
WIRE 16 -1 (-6050 3950)(-6250 3950);
WIRE 16 -1 (-6050 4000)(-6250 4000);
WIRE 16 -1 (-6250 4050)(-6050 4050);
WIRE 16 -1 (-6050 4100)(-6250 4100);
WIRE 16 -1 (-6050 4150)(-6250 4150);
WIRE 16 -1 (-6050 4200)(-6250 4200);
WIRE 16 -1 (-6250 4250)(-6050 4250);
WIRE 16 -1 (-6050 4300)(-6250 4300);
WIRE 16 -1 (-6050 4350)(-6250 4350);
WIRE 16 -1 (-6050 4400)(-6250 4400);
WIRE 16 -1 (-6250 4450)(-6050 4450);
WIRE 16 -1 (-6050 4500)(-6250 4500);
WIRE 16 -1 (-6050 4550)(-6250 4550);
WIRE 16 -1 (-6050 4600)(-6250 4600);
WIRE 16 -1 (-6250 4650)(-6050 4650);
WIRE 16 -1 (-6050 4700)(-6250 4700);
WIRE 16 -1 (-6050 4750)(-6250 4750);
WIRE 16 -1 (-6050 4800)(-6250 4800);
WIRE 16 -1 (-6250 4850)(-6050 4850);
WIRE 16 -1 (-6050 4900)(-6250 4900);
WIRE 16 -1 (-6050 4950)(-6250 4950);
WIRE 16 -1 (-6050 5000)(-6250 5000);
WIRE 16 -1 (-6250 5050)(-6050 5050);
WIRE 16 -1 (-6050 5100)(-6250 5100);
WIRE 16 -1 (-6050 5150)(-6250 5150);
WIRE 16 -1 (-6050 5200)(-6250 5200);
WIRE 16 -1 (-6250 5250)(-6050 5250);
WIRE 16 -1 (-6050 5300)(-6250 5300);
WIRE 16 -1 (-6050 5350)(-6250 5350);
WIRE 16 -1 (-6050 5400)(-6250 5400);
WIRE 16 -1 (-7450 4350)(-8250 4350);
FORCEPROP 2 LAST SIG_NAME M_I_CPU0_SB_CS_N<1>
J 0
(-8200 4360);
DISPLAY 0.489362 (-8200 4360);
WIRE 16 -1 (-7450 4500)(-8250 4500);
FORCEPROP 2 LAST SIG_NAME M_I_CPU0_SA_CS_N<1>
J 0
(-8200 4510);
DISPLAY 0.489362 (-8200 4510);
WIRE 16 -1 (-7450 4300)(-8250 4300);
FORCEPROP 2 LAST SIG_NAME M_I_CPU0_SB_CS_N<0>
J 0
(-8200 4310);
DISPLAY 0.489362 (-8200 4310);
WIRE 16 -1 (-7450 4450)(-8250 4450);
FORCEPROP 2 LAST SIG_NAME M_I_CPU0_SA_CS_N<0>
J 0
(-8200 4460);
DISPLAY 0.489362 (-8200 4460);
WIRE 16 -1 (-7450 4200)(-8250 4200);
FORCEPROP 2 LAST SIG_NAME M_I_CPU0_CLK_DP<0>
J 0
(-8200 4210);
DISPLAY 0.489362 (-8200 4210);
WIRE 16 -1 (-7450 4150)(-8250 4150);
FORCEPROP 2 LAST SIG_NAME M_I_CPU0_CLK_DN<0>
J 0
(-8200 4160);
DISPLAY 0.489362 (-8200 4160);
WIRE 16 -1 (-7450 3250)(-7650 3250);
WIRE 16 -1 (-7450 3300)(-7650 3300);
WIRE 16 -1 (-7450 3350)(-7650 3350);
WIRE 16 -1 (-7450 3400)(-7650 3400);
WIRE 16 -1 (-7450 3450)(-7650 3450);
WIRE 16 -1 (-7450 3500)(-7650 3500);
WIRE 16 -1 (-7450 3550)(-7650 3550);
WIRE 16 -1 (-7450 3700)(-7650 3700);
WIRE 16 -1 (-7450 3800)(-7650 3800);
WIRE 16 -1 (-7450 3850)(-7650 3850);
WIRE 16 -1 (-7450 3950)(-7650 3950);
WIRE 16 -1 (-7450 4000)(-7650 4000);
WIRE 16 -1 (-7450 5050)(-7650 5050);
WIRE 16 -1 (-7450 5450)(-7650 5450);
WIRE 16 -1 (-7450 5000)(-7650 5000);
WIRE 16 -1 (-7450 5400)(-7650 5400);
WIRE 16 -1 (-7450 4950)(-7650 4950);
WIRE 16 -1 (-7450 5350)(-7650 5350);
WIRE 16 -1 (-7450 4900)(-7650 4900);
WIRE 16 -1 (-7450 5300)(-7650 5300);
WIRE 16 -1 (-7450 4850)(-7650 4850);
WIRE 16 -1 (-7450 5250)(-7650 5250);
WIRE 16 -1 (-7450 4800)(-7650 4800);
WIRE 16 -1 (-7450 5200)(-7650 5200);
WIRE 16 -1 (-7450 4750)(-7650 4750);
WIRE 16 -1 (-7450 5150)(-7650 5150);
WIRE 16 -1 (-7450 3100)(-8075 3100);
FORCEPROP 2 LAST SIG_NAME M_I_CPU0_ALERT_N
J 0
(-8060 3110);
DISPLAY 0.489362 (-8060 3110);
WIRE 16 -1 (-7450 3600)(-7650 3600);
WIRE 16 -1 (-7450 3750)(-7650 3750);
WIRE 16 -1 (-7450 3900)(-7650 3900);
WIRE 16 -1 (-7450 4050)(-7650 4050);
WIRE 16 -1 (-6250 5450)(-6050 5450);
WIRE 16 -1 (-8975 2200)(-8575 2200);
FORCEPROP 2 LAST SIG_NAME PWRGD_CHGL_CPU0
J 0
(-8960 2210);
DISPLAY 0.489362 (-8960 2210);
WIRE 16 -1 (-2250 5675)(-2825 5675);
WIRE 16 -1 (-2250 5675)(-2250 5800);
WIRE 16 -1 (-2825 5675)(-2825 5800);
WIRE 16 -1 (-2825 5675)(-2825 5600);
DOT 1 (-8350 2200);
DOT 1 (-8550 3400);
DOT 1 (-2125 2200);
DOT 1 (-2125 2250);
DOT 1 (-2125 2300);
DOT 1 (-2125 2350);
DOT 1 (-2125 2400);
DOT 1 (-2125 2450);
DOT 1 (-2125 2500);
DOT 1 (-2125 2550);
DOT 1 (-2125 2600);
DOT 1 (-2125 2650);
DOT 1 (-2125 2700);
DOT 1 (-2125 2750);
DOT 1 (-2125 2800);
DOT 1 (-2125 2900);
DOT 1 (-2125 2850);
DOT 1 (-2125 2950);
DOT 1 (-2125 3000);
DOT 1 (-2125 3050);
DOT 1 (-2125 3100);
DOT 1 (-2125 3150);
DOT 1 (-2125 3200);
DOT 1 (-2125 3250);
DOT 1 (-2125 3300);
DOT 1 (-2125 3350);
DOT 1 (-2125 3400);
DOT 1 (-2125 3450);
DOT 1 (-2125 3500);
DOT 1 (-2125 3550);
DOT 1 (-2125 3600);
DOT 1 (-2125 3650);
DOT 1 (-2125 3700);
DOT 1 (-2125 3750);
DOT 1 (-2125 3800);
DOT 1 (-2125 3850);
DOT 1 (-2125 3900);
DOT 1 (-2125 3950);
DOT 1 (-325 2100);
DOT 1 (-325 2150);
DOT 1 (-325 2200);
DOT 1 (-325 2300);
DOT 1 (-325 2400);
DOT 1 (-325 2350);
DOT 1 (-325 2450);
DOT 1 (-325 2500);
DOT 1 (-325 2550);
DOT 1 (-325 2600);
DOT 1 (-325 2650);
DOT 1 (-325 2700);
DOT 1 (-325 2750);
DOT 1 (-325 2800);
DOT 1 (-325 2900);
DOT 1 (-325 2850);
DOT 1 (-325 2950);
DOT 1 (-325 3000);
DOT 1 (-325 3050);
DOT 1 (-325 3100);
DOT 1 (-325 3150);
DOT 1 (-325 3200);
DOT 1 (-325 3250);
DOT 1 (-325 3300);
DOT 1 (-325 3350);
DOT 1 (-325 3400);
DOT 1 (-325 3450);
DOT 1 (-325 3500);
DOT 1 (-325 3550);
DOT 1 (-325 3600);
DOT 1 (-325 3650);
DOT 1 (-325 3700);
DOT 1 (-325 3750);
DOT 1 (-325 3800);
DOT 1 (-325 3850);
DOT 1 (-325 3900);
DOT 1 (-325 3950);
DOT 1 (-2125 4050);
DOT 1 (-2125 4000);
DOT 1 (-2125 4100);
DOT 1 (-2125 4150);
DOT 1 (-2125 4200);
DOT 1 (-2125 4250);
DOT 1 (-2125 4300);
DOT 1 (-2125 4350);
DOT 1 (-2125 4400);
DOT 1 (-2125 4450);
DOT 1 (-2125 4500);
DOT 1 (-2125 4550);
DOT 1 (-2125 4600);
DOT 1 (-2125 4650);
DOT 1 (-2125 4750);
DOT 1 (-2125 4800);
DOT 1 (-2125 4950);
DOT 1 (-2125 4900);
DOT 1 (-2125 5000);
DOT 1 (-2125 5100);
DOT 1 (-2125 5150);
DOT 1 (-2125 5200);
DOT 1 (-2125 5250);
DOT 1 (-2125 5400);
DOT 1 (-325 4000);
DOT 1 (-325 4050);
DOT 1 (-325 4100);
DOT 1 (-325 4150);
DOT 1 (-325 4200);
DOT 1 (-325 4250);
DOT 1 (-325 4300);
DOT 1 (-325 4350);
DOT 1 (-325 4400);
DOT 1 (-325 4450);
DOT 1 (-325 4500);
DOT 1 (-325 4550);
DOT 1 (-325 4600);
DOT 1 (-325 4650);
DOT 1 (-325 4700);
DOT 1 (-325 4750);
DOT 1 (-325 4800);
DOT 1 (-325 4850);
DOT 1 (-325 4950);
DOT 1 (-325 4900);
DOT 1 (-325 5000);
DOT 1 (-325 5050);
DOT 1 (-325 5100);
DOT 1 (-325 5150);
DOT 1 (-325 5200);
DOT 1 (-325 5250);
DOT 1 (-325 5300);
DOT 1 (-325 5350);
DOT 1 (-2825 5675);
DOT 1 (-2825 6100);
DOT 1 (-2250 6100);
DOT 1 (-2125 4700);
DOT 1 (-2125 5050);
DOT 1 (-2125 4850);
DOT 1 (-325 5400);
DOT 1 (-2125 5450);
QUIT
